FILE_TYPE = MACRO_DRAWING;
SET COLOR_WIRE YELLOW;
SET COLOR_PROP MONO;
SET COLOR_DOT WHITE;
SET COLOR_ARC YELLOW;
SET COLOR_BODY GREEN;
SET COLOR_NOTE MONO;
SET PROP_DISPLAY VALUE;
SET PAGE_NUMBER P109;
FORCEADD OFFPAGE..5
(-2875 1950);
FORCEPROP 2 LAST $XR1 121 
J 0
(-3250 1950);
DISPLAY 0.638298 (-3250 1950);
PAINT MONO (-3250 1950);
FORCEPROP 2 LAST $XR0 133 
J 0
(-3130 1950);
DISPLAY 0.638298 (-3130 1950);
PAINT MONO (-3130 1950);
FORCEPROP 2 LAST PATH I1
J 0
(-3125 2000);
DISPLAY 1.021277 (-3125 2000);
PAINT ORANGE (-3125 2000);
DISPLAY INVISIBLE (-3125 2000);
FORCEPROP 1 LAST COMMENT_BODY TRUE
J 0
(-2775 1875);
DISPLAY 0.872340 (-2775 1875);
PAINT GREEN (-2775 1875);
DISPLAY INVISIBLE (-2775 1875);
FORCEPROP 1 LAST OFFPAGE TRUE
J 0
(-2550 1825);
DISPLAY 0.872340 (-2550 1825);
PAINT GREEN (-2550 1825);
DISPLAY INVISIBLE (-2550 1825);
FORCEPROP 2 LAST CDS_LIB mstr_standard
J 0
(-2875 1950);
PAINT MONO (-2875 1950);
DISPLAY INVISIBLE (-2875 1950);
FORCEADD TAP..1
R 2
(-2025 2350);
FORCEPROP 3 LASTPIN (-1975 2350) SIG_NAME P3E_CPU0_PE2_SS_C_TXP<5>
J 0
(-1965 2360);
DISPLAY 0.659574 (-1965 2360);
PAINT MONO (-1965 2360);
DISPLAY INVISIBLE (-1965 2360);
FORCEPROP 1 LASTPIN (-1975 2350) BN 5
J 2
(-1963 2358);
DISPLAY 0.617021 (-1963 2358);
PAINT GREEN (-1963 2358);
FORCEPROP 1 LAST PATH I10
J 2
(-2023 2350);
DISPLAY 0.872340 (-2023 2350);
PAINT GREEN (-2023 2350);
DISPLAY INVISIBLE (-2023 2350);
FORCEPROP 1 LAST HDL_TAP TRUE
J 2
(-2350 2225);
DISPLAY 0.872340 (-2350 2225);
PAINT ORANGE (-2350 2225);
DISPLAY INVISIBLE (-2350 2225);
FORCEPROP 1 LAST BODY_TYPE PLUMBING
J 2
(-2025 2400);
DISPLAY 0.872340 (-2025 2400);
PAINT GREEN (-2025 2400);
DISPLAY INVISIBLE (-2025 2400);
FORCEPROP 2 LAST CDS_LIB mstr_standard
J 0
(-2025 2350);
PAINT MONO (-2025 2350);
DISPLAY INVISIBLE (-2025 2350);
FORCEADD TAP..1
R 2
(-2275 2400);
FORCEPROP 3 LASTPIN (-2225 2400) SIG_NAME P3E_CPU0_PE2_SS_C_TXN<5>
J 0
(-2215 2410);
DISPLAY 0.659574 (-2215 2410);
PAINT MONO (-2215 2410);
DISPLAY INVISIBLE (-2215 2410);
FORCEPROP 1 LASTPIN (-2225 2400) BN 5
J 2
(-2213 2408);
DISPLAY 0.617021 (-2213 2408);
PAINT GREEN (-2213 2408);
FORCEPROP 1 LAST PATH I11
J 2
(-2273 2400);
DISPLAY 0.872340 (-2273 2400);
PAINT GREEN (-2273 2400);
DISPLAY INVISIBLE (-2273 2400);
FORCEPROP 1 LAST HDL_TAP TRUE
J 2
(-2600 2275);
DISPLAY 0.872340 (-2600 2275);
PAINT ORANGE (-2600 2275);
DISPLAY INVISIBLE (-2600 2275);
FORCEPROP 1 LAST BODY_TYPE PLUMBING
J 2
(-2275 2450);
DISPLAY 0.872340 (-2275 2450);
PAINT GREEN (-2275 2450);
DISPLAY INVISIBLE (-2275 2450);
FORCEPROP 2 LAST CDS_LIB mstr_standard
J 0
(-2275 2400);
PAINT MONO (-2275 2400);
DISPLAY INVISIBLE (-2275 2400);
FORCEADD TAP..1
R 2
(-2275 2550);
FORCEPROP 3 LASTPIN (-2225 2550) SIG_NAME P3E_CPU0_PE2_SS_C_TXN<4>
J 0
(-2215 2560);
DISPLAY 0.659574 (-2215 2560);
PAINT MONO (-2215 2560);
DISPLAY INVISIBLE (-2215 2560);
FORCEPROP 1 LASTPIN (-2225 2550) BN 4
J 2
(-2213 2558);
DISPLAY 0.617021 (-2213 2558);
PAINT GREEN (-2213 2558);
FORCEPROP 1 LAST PATH I12
J 2
(-2273 2550);
DISPLAY 0.872340 (-2273 2550);
PAINT GREEN (-2273 2550);
DISPLAY INVISIBLE (-2273 2550);
FORCEPROP 1 LAST HDL_TAP TRUE
J 2
(-2600 2425);
DISPLAY 0.872340 (-2600 2425);
PAINT ORANGE (-2600 2425);
DISPLAY INVISIBLE (-2600 2425);
FORCEPROP 1 LAST BODY_TYPE PLUMBING
J 2
(-2275 2600);
DISPLAY 0.872340 (-2275 2600);
PAINT GREEN (-2275 2600);
DISPLAY INVISIBLE (-2275 2600);
FORCEPROP 2 LAST CDS_LIB mstr_standard
J 0
(-2275 2550);
PAINT MONO (-2275 2550);
DISPLAY INVISIBLE (-2275 2550);
FORCEADD TAP..1
R 2
(-2275 2700);
FORCEPROP 3 LASTPIN (-2225 2700) SIG_NAME P3E_CPU0_PE2_SS_C_TXN<3>
J 0
(-2215 2710);
DISPLAY 0.659574 (-2215 2710);
PAINT MONO (-2215 2710);
DISPLAY INVISIBLE (-2215 2710);
FORCEPROP 1 LASTPIN (-2225 2700) BN 3
J 2
(-2213 2708);
DISPLAY 0.617021 (-2213 2708);
PAINT GREEN (-2213 2708);
FORCEPROP 1 LAST PATH I13
J 2
(-2273 2700);
DISPLAY 0.872340 (-2273 2700);
PAINT GREEN (-2273 2700);
DISPLAY INVISIBLE (-2273 2700);
FORCEPROP 1 LAST HDL_TAP TRUE
J 2
(-2600 2575);
DISPLAY 0.872340 (-2600 2575);
PAINT ORANGE (-2600 2575);
DISPLAY INVISIBLE (-2600 2575);
FORCEPROP 1 LAST BODY_TYPE PLUMBING
J 2
(-2275 2750);
DISPLAY 0.872340 (-2275 2750);
PAINT GREEN (-2275 2750);
DISPLAY INVISIBLE (-2275 2750);
FORCEPROP 2 LAST CDS_LIB mstr_standard
J 0
(-2275 2700);
PAINT MONO (-2275 2700);
DISPLAY INVISIBLE (-2275 2700);
FORCEADD TAP..1
R 2
(-2275 2850);
FORCEPROP 3 LASTPIN (-2225 2850) SIG_NAME P3E_CPU0_PE2_SS_C_TXN<2>
J 0
(-2215 2860);
DISPLAY 0.659574 (-2215 2860);
PAINT MONO (-2215 2860);
DISPLAY INVISIBLE (-2215 2860);
FORCEPROP 1 LASTPIN (-2225 2850) BN 2
J 2
(-2213 2858);
DISPLAY 0.617021 (-2213 2858);
PAINT GREEN (-2213 2858);
FORCEPROP 1 LAST PATH I14
J 2
(-2273 2850);
DISPLAY 0.872340 (-2273 2850);
PAINT GREEN (-2273 2850);
DISPLAY INVISIBLE (-2273 2850);
FORCEPROP 1 LAST HDL_TAP TRUE
J 2
(-2600 2725);
DISPLAY 0.872340 (-2600 2725);
PAINT ORANGE (-2600 2725);
DISPLAY INVISIBLE (-2600 2725);
FORCEPROP 1 LAST BODY_TYPE PLUMBING
J 2
(-2275 2900);
DISPLAY 0.872340 (-2275 2900);
PAINT GREEN (-2275 2900);
DISPLAY INVISIBLE (-2275 2900);
FORCEPROP 2 LAST CDS_LIB mstr_standard
J 0
(-2275 2850);
PAINT MONO (-2275 2850);
DISPLAY INVISIBLE (-2275 2850);
FORCEADD TAP..1
R 2
(-2275 2950);
FORCEPROP 3 LASTPIN (-2225 2950) SIG_NAME P3E_CPU0_PE2_SS_C_TXN<1>
J 0
(-2215 2960);
DISPLAY 0.659574 (-2215 2960);
PAINT MONO (-2215 2960);
DISPLAY INVISIBLE (-2215 2960);
FORCEPROP 1 LASTPIN (-2225 2950) BN 1
J 2
(-2213 2958);
DISPLAY 0.617021 (-2213 2958);
PAINT GREEN (-2213 2958);
FORCEPROP 1 LAST PATH I15
J 2
(-2273 2950);
DISPLAY 0.872340 (-2273 2950);
PAINT GREEN (-2273 2950);
DISPLAY INVISIBLE (-2273 2950);
FORCEPROP 1 LAST HDL_TAP TRUE
J 2
(-2600 2825);
DISPLAY 0.872340 (-2600 2825);
PAINT ORANGE (-2600 2825);
DISPLAY INVISIBLE (-2600 2825);
FORCEPROP 1 LAST BODY_TYPE PLUMBING
J 2
(-2275 3000);
DISPLAY 0.872340 (-2275 3000);
PAINT GREEN (-2275 3000);
DISPLAY INVISIBLE (-2275 3000);
FORCEPROP 2 LAST CDS_LIB mstr_standard
J 0
(-2275 2950);
PAINT MONO (-2275 2950);
DISPLAY INVISIBLE (-2275 2950);
FORCEADD TAP..1
R 2
(-2275 3150);
FORCEPROP 3 LASTPIN (-2225 3150) SIG_NAME P3E_CPU0_PE2_SS_C_TXN<0>
J 0
(-2215 3160);
DISPLAY 0.659574 (-2215 3160);
PAINT MONO (-2215 3160);
DISPLAY INVISIBLE (-2215 3160);
FORCEPROP 1 LASTPIN (-2225 3150) BN 0
J 2
(-2213 3158);
DISPLAY 0.617021 (-2213 3158);
PAINT GREEN (-2213 3158);
FORCEPROP 1 LAST PATH I16
J 2
(-2273 3150);
DISPLAY 0.872340 (-2273 3150);
PAINT GREEN (-2273 3150);
DISPLAY INVISIBLE (-2273 3150);
FORCEPROP 1 LAST HDL_TAP TRUE
J 2
(-2775 3025);
DISPLAY 0.872340 (-2775 3025);
PAINT ORANGE (-2775 3025);
DISPLAY INVISIBLE (-2775 3025);
FORCEPROP 1 LAST BODY_TYPE PLUMBING
J 2
(-2450 3200);
DISPLAY 0.872340 (-2450 3200);
PAINT GREEN (-2450 3200);
DISPLAY INVISIBLE (-2450 3200);
FORCEPROP 2 LAST CDS_LIB mstr_standard
J 0
(-2275 3150);
PAINT MONO (-2275 3150);
DISPLAY INVISIBLE (-2275 3150);
FORCEADD TAP..1
R 2
(-2275 3250);
FORCEPROP 3 LASTPIN (-2225 3250) SIG_NAME P3E_CPU0_PE1_SS_C_TXP<0>
J 0
(-2215 3260);
DISPLAY 0.659574 (-2215 3260);
PAINT MONO (-2215 3260);
DISPLAY INVISIBLE (-2215 3260);
FORCEPROP 1 LASTPIN (-2225 3250) BN 0
J 2
(-2213 3258);
DISPLAY 0.617021 (-2213 3258);
PAINT GREEN (-2213 3258);
FORCEPROP 1 LAST PATH I17
J 2
(-2273 3250);
DISPLAY 0.872340 (-2273 3250);
PAINT GREEN (-2273 3250);
DISPLAY INVISIBLE (-2273 3250);
FORCEPROP 1 LAST HDL_TAP TRUE
J 2
(-2600 3125);
DISPLAY 0.872340 (-2600 3125);
PAINT ORANGE (-2600 3125);
DISPLAY INVISIBLE (-2600 3125);
FORCEPROP 1 LAST BODY_TYPE PLUMBING
J 2
(-2275 3300);
DISPLAY 0.872340 (-2275 3300);
PAINT GREEN (-2275 3300);
DISPLAY INVISIBLE (-2275 3300);
FORCEPROP 2 LAST CDS_LIB mstr_standard
J 0
(-2275 3250);
PAINT MONO (-2275 3250);
DISPLAY INVISIBLE (-2275 3250);
FORCEADD TAP..1
R 2
(-2025 2650);
FORCEPROP 3 LASTPIN (-1975 2650) SIG_NAME P3E_CPU0_PE2_SS_C_TXP<3>
J 0
(-1965 2660);
DISPLAY 0.659574 (-1965 2660);
PAINT MONO (-1965 2660);
DISPLAY INVISIBLE (-1965 2660);
FORCEPROP 1 LASTPIN (-1975 2650) BN 3
J 2
(-1963 2658);
DISPLAY 0.617021 (-1963 2658);
PAINT GREEN (-1963 2658);
FORCEPROP 1 LAST PATH I18
J 2
(-2023 2650);
DISPLAY 0.872340 (-2023 2650);
PAINT GREEN (-2023 2650);
DISPLAY INVISIBLE (-2023 2650);
FORCEPROP 1 LAST HDL_TAP TRUE
J 2
(-2350 2525);
DISPLAY 0.872340 (-2350 2525);
PAINT ORANGE (-2350 2525);
DISPLAY INVISIBLE (-2350 2525);
FORCEPROP 1 LAST BODY_TYPE PLUMBING
J 2
(-2025 2700);
DISPLAY 0.872340 (-2025 2700);
PAINT GREEN (-2025 2700);
DISPLAY INVISIBLE (-2025 2700);
FORCEPROP 2 LAST CDS_LIB mstr_standard
J 0
(-2025 2650);
PAINT MONO (-2025 2650);
DISPLAY INVISIBLE (-2025 2650);
FORCEADD TAP..1
R 2
(-2025 2500);
FORCEPROP 3 LASTPIN (-1975 2500) SIG_NAME P3E_CPU0_PE2_SS_C_TXP<4>
J 0
(-1965 2510);
DISPLAY 0.659574 (-1965 2510);
PAINT MONO (-1965 2510);
DISPLAY INVISIBLE (-1965 2510);
FORCEPROP 1 LASTPIN (-1975 2500) BN 4
J 2
(-1963 2508);
DISPLAY 0.617021 (-1963 2508);
PAINT GREEN (-1963 2508);
FORCEPROP 1 LAST PATH I19
J 2
(-2023 2500);
DISPLAY 0.872340 (-2023 2500);
PAINT GREEN (-2023 2500);
DISPLAY INVISIBLE (-2023 2500);
FORCEPROP 1 LAST HDL_TAP TRUE
J 2
(-2350 2375);
DISPLAY 0.872340 (-2350 2375);
PAINT ORANGE (-2350 2375);
DISPLAY INVISIBLE (-2350 2375);
FORCEPROP 1 LAST BODY_TYPE PLUMBING
J 2
(-2025 2550);
DISPLAY 0.872340 (-2025 2550);
PAINT GREEN (-2025 2550);
DISPLAY INVISIBLE (-2025 2550);
FORCEPROP 2 LAST CDS_LIB mstr_standard
J 0
(-2025 2500);
PAINT MONO (-2025 2500);
DISPLAY INVISIBLE (-2025 2500);
FORCEADD OFFPAGE..1
(-3425 3100);
FORCEPROP 2 LAST $XR0 105 
J 0
(-3677 3100);
DISPLAY 0.638298 (-3677 3100);
PAINT MONO (-3677 3100);
FORCEPROP 2 LAST PATH I2
J 0
(-3675 3150);
DISPLAY 1.021277 (-3675 3150);
PAINT ORANGE (-3675 3150);
DISPLAY INVISIBLE (-3675 3150);
FORCEPROP 1 LAST COMMENT_BODY TRUE
J 0
(-3300 3000);
DISPLAY 0.872340 (-3300 3000);
PAINT GREEN (-3300 3000);
DISPLAY INVISIBLE (-3300 3000);
FORCEPROP 1 LAST OFFPAGE TRUE
J 0
(-3100 2975);
DISPLAY 0.872340 (-3100 2975);
PAINT GREEN (-3100 2975);
DISPLAY INVISIBLE (-3100 2975);
FORCEPROP 2 LAST CDS_LIB mstr_standard
J 2
(-3425 3100);
PAINT MONO (-3425 3100);
DISPLAY INVISIBLE (-3425 3100);
FORCEADD TAP..1
R 2
(-2025 2800);
FORCEPROP 3 LASTPIN (-1975 2800) SIG_NAME P3E_CPU0_PE2_SS_C_TXP<2>
J 0
(-1965 2810);
DISPLAY 0.659574 (-1965 2810);
PAINT MONO (-1965 2810);
DISPLAY INVISIBLE (-1965 2810);
FORCEPROP 1 LASTPIN (-1975 2800) BN 2
J 2
(-1963 2808);
DISPLAY 0.617021 (-1963 2808);
PAINT GREEN (-1963 2808);
FORCEPROP 1 LAST PATH I20
J 2
(-2023 2800);
DISPLAY 0.872340 (-2023 2800);
PAINT GREEN (-2023 2800);
DISPLAY INVISIBLE (-2023 2800);
FORCEPROP 1 LAST HDL_TAP TRUE
J 2
(-2350 2675);
DISPLAY 0.872340 (-2350 2675);
PAINT ORANGE (-2350 2675);
DISPLAY INVISIBLE (-2350 2675);
FORCEPROP 1 LAST BODY_TYPE PLUMBING
J 2
(-2025 2850);
DISPLAY 0.872340 (-2025 2850);
PAINT GREEN (-2025 2850);
DISPLAY INVISIBLE (-2025 2850);
FORCEPROP 2 LAST CDS_LIB mstr_standard
J 0
(-2025 2800);
PAINT MONO (-2025 2800);
DISPLAY INVISIBLE (-2025 2800);
FORCEADD TAP..1
R 2
(-2025 3000);
FORCEPROP 3 LASTPIN (-1975 3000) SIG_NAME P3E_CPU0_PE2_SS_C_TXP<1>
J 0
(-1965 3010);
DISPLAY 0.659574 (-1965 3010);
PAINT MONO (-1965 3010);
DISPLAY INVISIBLE (-1965 3010);
FORCEPROP 1 LASTPIN (-1975 3000) BN 1
J 2
(-1963 3008);
DISPLAY 0.617021 (-1963 3008);
PAINT GREEN (-1963 3008);
FORCEPROP 1 LAST PATH I21
J 2
(-2023 3000);
DISPLAY 0.872340 (-2023 3000);
PAINT GREEN (-2023 3000);
DISPLAY INVISIBLE (-2023 3000);
FORCEPROP 1 LAST HDL_TAP TRUE
J 2
(-2350 2875);
DISPLAY 0.872340 (-2350 2875);
PAINT ORANGE (-2350 2875);
DISPLAY INVISIBLE (-2350 2875);
FORCEPROP 1 LAST BODY_TYPE PLUMBING
J 2
(-2025 3050);
DISPLAY 0.872340 (-2025 3050);
PAINT GREEN (-2025 3050);
DISPLAY INVISIBLE (-2025 3050);
FORCEPROP 2 LAST CDS_LIB mstr_standard
J 0
(-2025 3000);
PAINT MONO (-2025 3000);
DISPLAY INVISIBLE (-2025 3000);
FORCEADD TAP..1
R 2
(-2025 3100);
FORCEPROP 3 LASTPIN (-1975 3100) SIG_NAME P3E_CPU0_PE2_SS_C_TXP<0>
J 0
(-1965 3110);
DISPLAY 0.659574 (-1965 3110);
PAINT MONO (-1965 3110);
DISPLAY INVISIBLE (-1965 3110);
FORCEPROP 1 LASTPIN (-1975 3100) BN 0
J 2
(-1963 3108);
DISPLAY 0.617021 (-1963 3108);
PAINT GREEN (-1963 3108);
FORCEPROP 1 LAST PATH I22
J 2
(-2023 3100);
DISPLAY 0.872340 (-2023 3100);
PAINT GREEN (-2023 3100);
DISPLAY INVISIBLE (-2023 3100);
FORCEPROP 1 LAST HDL_TAP TRUE
J 2
(-2350 2975);
DISPLAY 0.872340 (-2350 2975);
PAINT ORANGE (-2350 2975);
DISPLAY INVISIBLE (-2350 2975);
FORCEPROP 1 LAST BODY_TYPE PLUMBING
J 2
(-2025 3150);
DISPLAY 0.872340 (-2025 3150);
PAINT GREEN (-2025 3150);
DISPLAY INVISIBLE (-2025 3150);
FORCEPROP 2 LAST CDS_LIB mstr_standard
J 0
(-2025 3100);
PAINT MONO (-2025 3100);
DISPLAY INVISIBLE (-2025 3100);
FORCEADD TAP..1
R 2
(-2025 3300);
FORCEPROP 3 LASTPIN (-1975 3300) SIG_NAME P3E_CPU0_PE1_SS_C_TXN<0>
J 0
(-1965 3310);
DISPLAY 0.659574 (-1965 3310);
PAINT MONO (-1965 3310);
DISPLAY INVISIBLE (-1965 3310);
FORCEPROP 1 LASTPIN (-1975 3300) BN 0
J 2
(-1963 3308);
DISPLAY 0.617021 (-1963 3308);
PAINT GREEN (-1963 3308);
FORCEPROP 1 LAST PATH I23
J 2
(-2023 3300);
DISPLAY 0.872340 (-2023 3300);
PAINT GREEN (-2023 3300);
DISPLAY INVISIBLE (-2023 3300);
FORCEPROP 1 LAST HDL_TAP TRUE
J 2
(-2350 3175);
DISPLAY 0.872340 (-2350 3175);
PAINT ORANGE (-2350 3175);
DISPLAY INVISIBLE (-2350 3175);
FORCEPROP 1 LAST BODY_TYPE PLUMBING
J 2
(-2025 3350);
DISPLAY 0.872340 (-2025 3350);
PAINT GREEN (-2025 3350);
DISPLAY INVISIBLE (-2025 3350);
FORCEPROP 2 LAST CDS_LIB mstr_standard
J 0
(-2025 3300);
PAINT MONO (-2025 3300);
DISPLAY INVISIBLE (-2025 3300);
FORCEADD TAP..1
R 2
(-2025 3400);
FORCEPROP 3 LASTPIN (-1975 3400) SIG_NAME P3E_CPU0_PE1_SS_C_TXN<1>
J 0
(-1965 3410);
DISPLAY 0.659574 (-1965 3410);
PAINT MONO (-1965 3410);
DISPLAY INVISIBLE (-1965 3410);
FORCEPROP 1 LASTPIN (-1975 3400) BN 1
J 2
(-1963 3408);
DISPLAY 0.617021 (-1963 3408);
PAINT GREEN (-1963 3408);
FORCEPROP 1 LAST PATH I24
J 2
(-2023 3400);
DISPLAY 0.872340 (-2023 3400);
PAINT GREEN (-2023 3400);
DISPLAY INVISIBLE (-2023 3400);
FORCEPROP 1 LAST HDL_TAP TRUE
J 2
(-2350 3275);
DISPLAY 0.872340 (-2350 3275);
PAINT ORANGE (-2350 3275);
DISPLAY INVISIBLE (-2350 3275);
FORCEPROP 1 LAST BODY_TYPE PLUMBING
J 2
(-2025 3450);
DISPLAY 0.872340 (-2025 3450);
PAINT GREEN (-2025 3450);
DISPLAY INVISIBLE (-2025 3450);
FORCEPROP 2 LAST CDS_LIB mstr_standard
J 0
(-2025 3400);
PAINT MONO (-2025 3400);
DISPLAY INVISIBLE (-2025 3400);
FORCEADD GND..1
(-1500 1700);
FORCEPROP 3 LASTPIN (-1500 1750) SIG_NAME GND\g
J 0
(-1490 1760);
DISPLAY 0.659574 (-1490 1760);
PAINT MONO (-1490 1760);
DISPLAY INVISIBLE (-1490 1760);
FORCEPROP 1 LAST PATH I25
J 0
(-1425 1700);
DISPLAY 0.872340 (-1425 1700);
PAINT AQUA (-1425 1700);
DISPLAY INVISIBLE (-1425 1700);
FORCEPROP 1 LAST BODY_TYPE PLUMBING
J 0
(-1545 1657);
DISPLAY 0.340426 (-1545 1657);
PAINT GREEN (-1545 1657);
DISPLAY INVISIBLE (-1545 1657);
FORCEPROP 1 LAST HDL_POWER GND
J 0
(-1500 1850);
DISPLAY 0.872340 (-1500 1850);
PAINT GREEN (-1500 1850);
DISPLAY INVISIBLE (-1500 1850);
FORCEPROP 1 LAST VOLTAGE 0
J 0
(-1500 1700);
PAINT SKYBLUE (-1500 1700);
DISPLAY INVISIBLE (-1500 1700);
FORCEPROP 2 LAST CDS_LIB mstr_symbols
J 0
(-1500 1700);
PAINT MONO (-1500 1700);
DISPLAY INVISIBLE (-1500 1700);
FORCEPROP 1 LAST SIZE 1B
J 0
(-1425 1650);
DISPLAY 0.872340 (-1425 1650);
PAINT AQUA (-1425 1650);
DISPLAY INVISIBLE (-1425 1650);
FORCEADD GND..1
(-450 1700);
FORCEPROP 3 LASTPIN (-450 1750) SIG_NAME GND\g
J 0
(-440 1760);
DISPLAY 0.659574 (-440 1760);
PAINT MONO (-440 1760);
DISPLAY INVISIBLE (-440 1760);
FORCEPROP 1 LAST PATH I26
J 0
(-375 1700);
DISPLAY 0.872340 (-375 1700);
PAINT AQUA (-375 1700);
DISPLAY INVISIBLE (-375 1700);
FORCEPROP 1 LAST BODY_TYPE PLUMBING
J 0
(-495 1657);
DISPLAY 0.340426 (-495 1657);
PAINT GREEN (-495 1657);
DISPLAY INVISIBLE (-495 1657);
FORCEPROP 1 LAST HDL_POWER GND
J 0
(-450 1850);
DISPLAY 0.872340 (-450 1850);
PAINT GREEN (-450 1850);
DISPLAY INVISIBLE (-450 1850);
FORCEPROP 1 LAST VOLTAGE 0
J 0
(-450 1700);
PAINT SKYBLUE (-450 1700);
DISPLAY INVISIBLE (-450 1700);
FORCEPROP 1 LAST SIZE 1B
J 0
(-375 1650);
DISPLAY 0.872340 (-375 1650);
PAINT AQUA (-375 1650);
DISPLAY INVISIBLE (-375 1650);
FORCEPROP 2 LAST CDS_LIB mstr_symbols
J 0
(-450 1700);
PAINT MONO (-450 1700);
DISPLAY INVISIBLE (-450 1700);
FORCEADD TAP..1
(-250 2050);
FORCEPROP 3 LASTPIN (-300 2050) SIG_NAME P3E_CPU0_PE2_SS_RXN<7>
J 0
(-290 2060);
DISPLAY 0.659574 (-290 2060);
PAINT MONO (-290 2060);
DISPLAY INVISIBLE (-290 2060);
FORCEPROP 1 LASTPIN (-300 2050) BN 7
J 0
(-312 2058);
DISPLAY 0.617021 (-312 2058);
PAINT GREEN (-312 2058);
FORCEPROP 1 LAST PATH I27
J 0
(-252 2050);
DISPLAY 0.872340 (-252 2050);
PAINT GREEN (-252 2050);
DISPLAY INVISIBLE (-252 2050);
FORCEPROP 1 LAST HDL_TAP TRUE
J 0
(250 1925);
DISPLAY 0.872340 (250 1925);
PAINT ORANGE (250 1925);
DISPLAY INVISIBLE (250 1925);
FORCEPROP 1 LAST BODY_TYPE PLUMBING
J 0
(-75 2100);
DISPLAY 0.872340 (-75 2100);
PAINT GREEN (-75 2100);
DISPLAY INVISIBLE (-75 2100);
FORCEPROP 2 LAST CDS_LIB mstr_standard
J 0
(-250 2050);
PAINT MONO (-250 2050);
DISPLAY INVISIBLE (-250 2050);
FORCEADD TAP..1
(-250 2350);
FORCEPROP 3 LASTPIN (-300 2350) SIG_NAME P3E_CPU0_PE2_SS_RXN<5>
J 0
(-290 2360);
DISPLAY 0.659574 (-290 2360);
PAINT MONO (-290 2360);
DISPLAY INVISIBLE (-290 2360);
FORCEPROP 1 LASTPIN (-300 2350) BN 5
J 0
(-312 2358);
DISPLAY 0.617021 (-312 2358);
PAINT GREEN (-312 2358);
FORCEPROP 1 LAST PATH I28
J 0
(-252 2350);
DISPLAY 0.872340 (-252 2350);
PAINT GREEN (-252 2350);
DISPLAY INVISIBLE (-252 2350);
FORCEPROP 1 LAST HDL_TAP TRUE
J 0
(250 2225);
DISPLAY 0.872340 (250 2225);
PAINT ORANGE (250 2225);
DISPLAY INVISIBLE (250 2225);
FORCEPROP 1 LAST BODY_TYPE PLUMBING
J 0
(-75 2400);
DISPLAY 0.872340 (-75 2400);
PAINT GREEN (-75 2400);
DISPLAY INVISIBLE (-75 2400);
FORCEPROP 2 LAST CDS_LIB mstr_standard
J 0
(-250 2350);
PAINT MONO (-250 2350);
DISPLAY INVISIBLE (-250 2350);
FORCEADD TAP..1
(-250 2150);
FORCEPROP 3 LASTPIN (-300 2150) SIG_NAME P3E_CPU0_PE2_SS_RXN<6>
J 0
(-290 2160);
DISPLAY 0.659574 (-290 2160);
PAINT MONO (-290 2160);
DISPLAY INVISIBLE (-290 2160);
FORCEPROP 1 LASTPIN (-300 2150) BN 6
J 0
(-312 2158);
DISPLAY 0.617021 (-312 2158);
PAINT GREEN (-312 2158);
FORCEPROP 1 LAST PATH I29
J 0
(-252 2150);
DISPLAY 0.872340 (-252 2150);
PAINT GREEN (-252 2150);
DISPLAY INVISIBLE (-252 2150);
FORCEPROP 1 LAST HDL_TAP TRUE
J 0
(250 2025);
DISPLAY 0.872340 (250 2025);
PAINT ORANGE (250 2025);
DISPLAY INVISIBLE (250 2025);
FORCEPROP 1 LAST BODY_TYPE PLUMBING
J 0
(-75 2200);
DISPLAY 0.872340 (-75 2200);
PAINT GREEN (-75 2200);
DISPLAY INVISIBLE (-75 2200);
FORCEPROP 2 LAST CDS_LIB mstr_standard
J 0
(-250 2150);
PAINT MONO (-250 2150);
DISPLAY INVISIBLE (-250 2150);
FORCEADD OFFPAGE..1
(-3425 3175);
FORCEPROP 2 LAST $XR0 105 
J 0
(-3677 3175);
DISPLAY 0.638298 (-3677 3175);
PAINT MONO (-3677 3175);
FORCEPROP 2 LAST PATH I3
J 0
(-3675 3225);
DISPLAY 1.021277 (-3675 3225);
PAINT ORANGE (-3675 3225);
DISPLAY INVISIBLE (-3675 3225);
FORCEPROP 1 LAST COMMENT_BODY TRUE
J 0
(-3300 3075);
DISPLAY 0.872340 (-3300 3075);
PAINT GREEN (-3300 3075);
DISPLAY INVISIBLE (-3300 3075);
FORCEPROP 1 LAST OFFPAGE TRUE
J 0
(-3100 3050);
DISPLAY 0.872340 (-3100 3050);
PAINT GREEN (-3100 3050);
DISPLAY INVISIBLE (-3100 3050);
FORCEPROP 2 LAST CDS_LIB mstr_standard
J 2
(-3425 3175);
PAINT MONO (-3425 3175);
DISPLAY INVISIBLE (-3425 3175);
FORCEADD TAP..1
(-25 2000);
FORCEPROP 3 LASTPIN (-75 2000) SIG_NAME P3E_CPU0_PE2_SS_RXP<7>
J 0
(-65 2010);
DISPLAY 0.659574 (-65 2010);
PAINT MONO (-65 2010);
DISPLAY INVISIBLE (-65 2010);
FORCEPROP 1 LASTPIN (-75 2000) BN 7
J 0
(-87 2008);
DISPLAY 0.617021 (-87 2008);
PAINT GREEN (-87 2008);
FORCEPROP 1 LAST PATH I30
J 0
(-27 2000);
DISPLAY 0.872340 (-27 2000);
PAINT GREEN (-27 2000);
DISPLAY INVISIBLE (-27 2000);
FORCEPROP 1 LAST HDL_TAP TRUE
J 0
(475 1875);
DISPLAY 0.872340 (475 1875);
PAINT ORANGE (475 1875);
DISPLAY INVISIBLE (475 1875);
FORCEPROP 1 LAST BODY_TYPE PLUMBING
J 0
(150 2050);
DISPLAY 0.872340 (150 2050);
PAINT GREEN (150 2050);
DISPLAY INVISIBLE (150 2050);
FORCEPROP 2 LAST CDS_LIB mstr_standard
J 0
(-25 2000);
PAINT MONO (-25 2000);
DISPLAY INVISIBLE (-25 2000);
FORCEADD TAP..1
(-25 2300);
FORCEPROP 3 LASTPIN (-75 2300) SIG_NAME P3E_CPU0_PE2_SS_RXP<5>
J 0
(-65 2310);
DISPLAY 0.659574 (-65 2310);
PAINT MONO (-65 2310);
DISPLAY INVISIBLE (-65 2310);
FORCEPROP 1 LASTPIN (-75 2300) BN 5
J 0
(-87 2308);
DISPLAY 0.617021 (-87 2308);
PAINT GREEN (-87 2308);
FORCEPROP 1 LAST PATH I31
J 0
(-27 2300);
DISPLAY 0.872340 (-27 2300);
PAINT GREEN (-27 2300);
DISPLAY INVISIBLE (-27 2300);
FORCEPROP 1 LAST HDL_TAP TRUE
J 0
(475 2175);
DISPLAY 0.872340 (475 2175);
PAINT ORANGE (475 2175);
DISPLAY INVISIBLE (475 2175);
FORCEPROP 1 LAST BODY_TYPE PLUMBING
J 0
(150 2350);
DISPLAY 0.872340 (150 2350);
PAINT GREEN (150 2350);
DISPLAY INVISIBLE (150 2350);
FORCEPROP 2 LAST CDS_LIB mstr_standard
J 0
(-25 2300);
PAINT MONO (-25 2300);
DISPLAY INVISIBLE (-25 2300);
FORCEADD TAP..1
(-25 2200);
FORCEPROP 3 LASTPIN (-75 2200) SIG_NAME P3E_CPU0_PE2_SS_RXP<6>
J 0
(-65 2210);
DISPLAY 0.659574 (-65 2210);
PAINT MONO (-65 2210);
DISPLAY INVISIBLE (-65 2210);
FORCEPROP 1 LASTPIN (-75 2200) BN 6
J 0
(-87 2208);
DISPLAY 0.617021 (-87 2208);
PAINT GREEN (-87 2208);
FORCEPROP 1 LAST PATH I32
J 0
(-27 2200);
DISPLAY 0.872340 (-27 2200);
PAINT GREEN (-27 2200);
DISPLAY INVISIBLE (-27 2200);
FORCEPROP 1 LAST HDL_TAP TRUE
J 0
(475 2075);
DISPLAY 0.872340 (475 2075);
PAINT ORANGE (475 2075);
DISPLAY INVISIBLE (475 2075);
FORCEPROP 1 LAST BODY_TYPE PLUMBING
J 0
(150 2250);
DISPLAY 0.872340 (150 2250);
PAINT GREEN (150 2250);
DISPLAY INVISIBLE (150 2250);
FORCEPROP 2 LAST CDS_LIB mstr_standard
J 0
(-25 2200);
PAINT MONO (-25 2200);
DISPLAY INVISIBLE (-25 2200);
FORCEADD TAP..1
(-250 2500);
FORCEPROP 3 LASTPIN (-300 2500) SIG_NAME P3E_CPU0_PE2_SS_RXN<4>
J 0
(-290 2510);
DISPLAY 0.659574 (-290 2510);
PAINT MONO (-290 2510);
DISPLAY INVISIBLE (-290 2510);
FORCEPROP 1 LASTPIN (-300 2500) BN 4
J 0
(-312 2508);
DISPLAY 0.617021 (-312 2508);
PAINT GREEN (-312 2508);
FORCEPROP 1 LAST PATH I33
J 0
(-252 2500);
DISPLAY 0.872340 (-252 2500);
PAINT GREEN (-252 2500);
DISPLAY INVISIBLE (-252 2500);
FORCEPROP 1 LAST HDL_TAP TRUE
J 0
(250 2375);
DISPLAY 0.872340 (250 2375);
PAINT ORANGE (250 2375);
DISPLAY INVISIBLE (250 2375);
FORCEPROP 1 LAST BODY_TYPE PLUMBING
J 0
(-75 2550);
DISPLAY 0.872340 (-75 2550);
PAINT GREEN (-75 2550);
DISPLAY INVISIBLE (-75 2550);
FORCEPROP 2 LAST CDS_LIB mstr_standard
J 0
(-250 2500);
PAINT MONO (-250 2500);
DISPLAY INVISIBLE (-250 2500);
FORCEADD TAP..1
(-250 2650);
FORCEPROP 3 LASTPIN (-300 2650) SIG_NAME P3E_CPU0_PE2_SS_RXN<3>
J 0
(-290 2660);
DISPLAY 0.659574 (-290 2660);
PAINT MONO (-290 2660);
DISPLAY INVISIBLE (-290 2660);
FORCEPROP 1 LASTPIN (-300 2650) BN 3
J 0
(-312 2658);
DISPLAY 0.617021 (-312 2658);
PAINT GREEN (-312 2658);
FORCEPROP 1 LAST PATH I34
J 0
(-252 2650);
DISPLAY 0.872340 (-252 2650);
PAINT GREEN (-252 2650);
DISPLAY INVISIBLE (-252 2650);
FORCEPROP 1 LAST HDL_TAP TRUE
J 0
(250 2525);
DISPLAY 0.872340 (250 2525);
PAINT ORANGE (250 2525);
DISPLAY INVISIBLE (250 2525);
FORCEPROP 1 LAST BODY_TYPE PLUMBING
J 0
(-75 2700);
DISPLAY 0.872340 (-75 2700);
PAINT GREEN (-75 2700);
DISPLAY INVISIBLE (-75 2700);
FORCEPROP 2 LAST CDS_LIB mstr_standard
J 0
(-250 2650);
PAINT MONO (-250 2650);
DISPLAY INVISIBLE (-250 2650);
FORCEADD TAP..1
(-250 2750);
FORCEPROP 3 LASTPIN (-300 2750) SIG_NAME P3E_CPU0_PE2_SS_RXN<2>
J 0
(-290 2760);
DISPLAY 0.659574 (-290 2760);
PAINT MONO (-290 2760);
DISPLAY INVISIBLE (-290 2760);
FORCEPROP 1 LASTPIN (-300 2750) BN 2
J 0
(-312 2758);
DISPLAY 0.617021 (-312 2758);
PAINT GREEN (-312 2758);
FORCEPROP 1 LAST PATH I35
J 0
(-252 2750);
DISPLAY 0.872340 (-252 2750);
PAINT GREEN (-252 2750);
DISPLAY INVISIBLE (-252 2750);
FORCEPROP 1 LAST HDL_TAP TRUE
J 0
(250 2625);
DISPLAY 0.872340 (250 2625);
PAINT ORANGE (250 2625);
DISPLAY INVISIBLE (250 2625);
FORCEPROP 1 LAST BODY_TYPE PLUMBING
J 0
(-75 2800);
DISPLAY 0.872340 (-75 2800);
PAINT GREEN (-75 2800);
DISPLAY INVISIBLE (-75 2800);
FORCEPROP 2 LAST CDS_LIB mstr_standard
J 0
(-250 2750);
PAINT MONO (-250 2750);
DISPLAY INVISIBLE (-250 2750);
FORCEADD TAP..1
(-250 3100);
FORCEPROP 3 LASTPIN (-300 3100) SIG_NAME P3E_CPU0_PE2_SS_RXN<0>
J 0
(-290 3110);
DISPLAY 0.659574 (-290 3110);
PAINT MONO (-290 3110);
DISPLAY INVISIBLE (-290 3110);
FORCEPROP 1 LASTPIN (-300 3100) BN 0
J 0
(-312 3108);
DISPLAY 0.617021 (-312 3108);
PAINT GREEN (-312 3108);
FORCEPROP 1 LAST PATH I36
J 0
(-252 3100);
DISPLAY 0.872340 (-252 3100);
PAINT GREEN (-252 3100);
DISPLAY INVISIBLE (-252 3100);
FORCEPROP 1 LAST HDL_TAP TRUE
J 0
(250 2975);
DISPLAY 0.872340 (250 2975);
PAINT ORANGE (250 2975);
DISPLAY INVISIBLE (250 2975);
FORCEPROP 1 LAST BODY_TYPE PLUMBING
J 0
(-75 3150);
DISPLAY 0.872340 (-75 3150);
PAINT GREEN (-75 3150);
DISPLAY INVISIBLE (-75 3150);
FORCEPROP 2 LAST CDS_LIB mstr_standard
J 0
(-250 3100);
PAINT MONO (-250 3100);
DISPLAY INVISIBLE (-250 3100);
FORCEADD TAP..1
(-250 3250);
FORCEPROP 3 LASTPIN (-300 3250) SIG_NAME P3E_CPU0_PE1_SS_R_RXN<0>
J 0
(-290 3260);
DISPLAY 0.659574 (-290 3260);
PAINT MONO (-290 3260);
DISPLAY INVISIBLE (-290 3260);
FORCEPROP 1 LASTPIN (-300 3250) BN 0
J 0
(-312 3258);
DISPLAY 0.617021 (-312 3258);
PAINT GREEN (-312 3258);
FORCEPROP 1 LAST PATH I37
J 0
(-252 3250);
DISPLAY 0.872340 (-252 3250);
PAINT GREEN (-252 3250);
DISPLAY INVISIBLE (-252 3250);
FORCEPROP 1 LAST HDL_TAP TRUE
J 0
(250 3125);
DISPLAY 0.872340 (250 3125);
PAINT ORANGE (250 3125);
DISPLAY INVISIBLE (250 3125);
FORCEPROP 1 LAST BODY_TYPE PLUMBING
J 0
(-75 3300);
DISPLAY 0.872340 (-75 3300);
PAINT GREEN (-75 3300);
DISPLAY INVISIBLE (-75 3300);
FORCEPROP 2 LAST CDS_LIB mstr_standard
J 0
(-250 3250);
PAINT MONO (-250 3250);
DISPLAY INVISIBLE (-250 3250);
FORCEADD TAP..1
(-250 3400);
FORCEPROP 3 LASTPIN (-300 3400) SIG_NAME P3E_CPU0_PE1_SS_R_RXN<1>
J 0
(-290 3410);
DISPLAY 0.659574 (-290 3410);
PAINT MONO (-290 3410);
DISPLAY INVISIBLE (-290 3410);
FORCEPROP 1 LASTPIN (-300 3400) BN 1
J 0
(-312 3408);
DISPLAY 0.617021 (-312 3408);
PAINT GREEN (-312 3408);
FORCEPROP 1 LAST PATH I38
J 0
(-252 3400);
DISPLAY 0.872340 (-252 3400);
PAINT GREEN (-252 3400);
DISPLAY INVISIBLE (-252 3400);
FORCEPROP 1 LAST HDL_TAP TRUE
J 0
(250 3275);
DISPLAY 0.872340 (250 3275);
PAINT ORANGE (250 3275);
DISPLAY INVISIBLE (250 3275);
FORCEPROP 1 LAST BODY_TYPE PLUMBING
J 0
(-75 3450);
DISPLAY 0.872340 (-75 3450);
PAINT GREEN (-75 3450);
DISPLAY INVISIBLE (-75 3450);
FORCEPROP 2 LAST CDS_LIB mstr_standard
J 0
(-250 3400);
PAINT MONO (-250 3400);
DISPLAY INVISIBLE (-250 3400);
FORCEADD TAP..1
(-25 2450);
FORCEPROP 3 LASTPIN (-75 2450) SIG_NAME P3E_CPU0_PE2_SS_RXP<4>
J 0
(-65 2460);
DISPLAY 0.659574 (-65 2460);
PAINT MONO (-65 2460);
DISPLAY INVISIBLE (-65 2460);
FORCEPROP 1 LASTPIN (-75 2450) BN 4
J 0
(-87 2458);
DISPLAY 0.617021 (-87 2458);
PAINT GREEN (-87 2458);
FORCEPROP 1 LAST PATH I39
J 0
(-27 2450);
DISPLAY 0.872340 (-27 2450);
PAINT GREEN (-27 2450);
DISPLAY INVISIBLE (-27 2450);
FORCEPROP 1 LAST HDL_TAP TRUE
J 0
(475 2325);
DISPLAY 0.872340 (475 2325);
PAINT ORANGE (475 2325);
DISPLAY INVISIBLE (475 2325);
FORCEPROP 1 LAST BODY_TYPE PLUMBING
J 0
(150 2500);
DISPLAY 0.872340 (150 2500);
PAINT GREEN (150 2500);
DISPLAY INVISIBLE (150 2500);
FORCEPROP 2 LAST CDS_LIB mstr_standard
J 0
(-25 2450);
PAINT MONO (-25 2450);
DISPLAY INVISIBLE (-25 2450);
FORCEADD OFFPAGE..1
(-3450 4425);
FORCEPROP 2 LAST $XR0 107 
J 0
(-3702 4425);
DISPLAY 0.638298 (-3702 4425);
PAINT MONO (-3702 4425);
FORCEPROP 2 LAST PATH I4
J 0
(-3700 4475);
DISPLAY 1.021277 (-3700 4475);
PAINT ORANGE (-3700 4475);
DISPLAY INVISIBLE (-3700 4475);
FORCEPROP 1 LAST COMMENT_BODY TRUE
J 0
(-3325 4325);
DISPLAY 0.872340 (-3325 4325);
PAINT GREEN (-3325 4325);
DISPLAY INVISIBLE (-3325 4325);
FORCEPROP 1 LAST OFFPAGE TRUE
J 0
(-3125 4300);
DISPLAY 0.872340 (-3125 4300);
PAINT GREEN (-3125 4300);
DISPLAY INVISIBLE (-3125 4300);
FORCEPROP 2 LAST CDS_LIB mstr_standard
J 2
(-3450 4425);
PAINT MONO (-3450 4425);
DISPLAY INVISIBLE (-3450 4425);
FORCEADD TAP..1
(-25 2800);
FORCEPROP 3 LASTPIN (-75 2800) SIG_NAME P3E_CPU0_PE2_SS_RXP<2>
J 0
(-65 2810);
DISPLAY 0.659574 (-65 2810);
PAINT MONO (-65 2810);
DISPLAY INVISIBLE (-65 2810);
FORCEPROP 1 LASTPIN (-75 2800) BN 2
J 0
(-87 2808);
DISPLAY 0.617021 (-87 2808);
PAINT GREEN (-87 2808);
FORCEPROP 1 LAST PATH I40
J 0
(-27 2800);
DISPLAY 0.872340 (-27 2800);
PAINT GREEN (-27 2800);
DISPLAY INVISIBLE (-27 2800);
FORCEPROP 1 LAST HDL_TAP TRUE
J 0
(475 2675);
DISPLAY 0.872340 (475 2675);
PAINT ORANGE (475 2675);
DISPLAY INVISIBLE (475 2675);
FORCEPROP 1 LAST BODY_TYPE PLUMBING
J 0
(150 2850);
DISPLAY 0.872340 (150 2850);
PAINT GREEN (150 2850);
DISPLAY INVISIBLE (150 2850);
FORCEPROP 2 LAST CDS_LIB mstr_standard
J 0
(-25 2800);
PAINT MONO (-25 2800);
DISPLAY INVISIBLE (-25 2800);
FORCEADD TAP..1
(-25 2900);
FORCEPROP 3 LASTPIN (-75 2900) SIG_NAME P3E_CPU0_PE2_SS_RXP<1>
J 0
(-65 2910);
DISPLAY 0.659574 (-65 2910);
PAINT MONO (-65 2910);
DISPLAY INVISIBLE (-65 2910);
FORCEPROP 1 LASTPIN (-75 2900) BN 1
J 0
(-87 2908);
DISPLAY 0.617021 (-87 2908);
PAINT GREEN (-87 2908);
FORCEPROP 1 LAST PATH I41
J 0
(-27 2900);
DISPLAY 0.872340 (-27 2900);
PAINT GREEN (-27 2900);
DISPLAY INVISIBLE (-27 2900);
FORCEPROP 1 LAST HDL_TAP TRUE
J 0
(475 2775);
DISPLAY 0.872340 (475 2775);
PAINT ORANGE (475 2775);
DISPLAY INVISIBLE (475 2775);
FORCEPROP 1 LAST BODY_TYPE PLUMBING
J 0
(150 2950);
DISPLAY 0.872340 (150 2950);
PAINT GREEN (150 2950);
DISPLAY INVISIBLE (150 2950);
FORCEPROP 2 LAST CDS_LIB mstr_standard
J 0
(-25 2900);
PAINT MONO (-25 2900);
DISPLAY INVISIBLE (-25 2900);
FORCEADD TAP..1
(-25 3050);
FORCEPROP 3 LASTPIN (-75 3050) SIG_NAME P3E_CPU0_PE2_SS_RXP<0>
J 0
(-65 3060);
DISPLAY 0.659574 (-65 3060);
PAINT MONO (-65 3060);
DISPLAY INVISIBLE (-65 3060);
FORCEPROP 1 LASTPIN (-75 3050) BN 0
J 0
(-87 3058);
DISPLAY 0.617021 (-87 3058);
PAINT GREEN (-87 3058);
FORCEPROP 1 LAST PATH I42
J 0
(-27 3050);
DISPLAY 0.872340 (-27 3050);
PAINT GREEN (-27 3050);
DISPLAY INVISIBLE (-27 3050);
FORCEPROP 1 LAST HDL_TAP TRUE
J 0
(475 2925);
DISPLAY 0.872340 (475 2925);
PAINT ORANGE (475 2925);
DISPLAY INVISIBLE (475 2925);
FORCEPROP 1 LAST BODY_TYPE PLUMBING
J 0
(150 3100);
DISPLAY 0.872340 (150 3100);
PAINT GREEN (150 3100);
DISPLAY INVISIBLE (150 3100);
FORCEPROP 2 LAST CDS_LIB mstr_standard
J 0
(-25 3050);
PAINT MONO (-25 3050);
DISPLAY INVISIBLE (-25 3050);
FORCEADD TAP..1
(-25 3350);
FORCEPROP 3 LASTPIN (-75 3350) SIG_NAME P3E_CPU0_PE1_SS_R_RXP<1>
J 0
(-65 3360);
DISPLAY 0.659574 (-65 3360);
PAINT MONO (-65 3360);
DISPLAY INVISIBLE (-65 3360);
FORCEPROP 1 LASTPIN (-75 3350) BN 1
J 0
(-87 3358);
DISPLAY 0.617021 (-87 3358);
PAINT GREEN (-87 3358);
FORCEPROP 1 LAST PATH I43
J 0
(-27 3350);
DISPLAY 0.872340 (-27 3350);
PAINT GREEN (-27 3350);
DISPLAY INVISIBLE (-27 3350);
FORCEPROP 1 LAST HDL_TAP TRUE
J 0
(475 3225);
DISPLAY 0.872340 (475 3225);
PAINT ORANGE (475 3225);
DISPLAY INVISIBLE (475 3225);
FORCEPROP 1 LAST BODY_TYPE PLUMBING
J 0
(150 3400);
DISPLAY 0.872340 (150 3400);
PAINT GREEN (150 3400);
DISPLAY INVISIBLE (150 3400);
FORCEPROP 2 LAST CDS_LIB mstr_standard
J 0
(-25 3350);
PAINT MONO (-25 3350);
DISPLAY INVISIBLE (-25 3350);
FORCEADD TAP..1
(-25 3200);
FORCEPROP 3 LASTPIN (-75 3200) SIG_NAME P3E_CPU0_PE1_SS_R_RXP<0>
J 0
(-65 3210);
DISPLAY 0.659574 (-65 3210);
PAINT MONO (-65 3210);
DISPLAY INVISIBLE (-65 3210);
FORCEPROP 1 LASTPIN (-75 3200) BN 0
J 0
(-87 3208);
DISPLAY 0.617021 (-87 3208);
PAINT GREEN (-87 3208);
FORCEPROP 1 LAST PATH I44
J 0
(-27 3200);
DISPLAY 0.872340 (-27 3200);
PAINT GREEN (-27 3200);
DISPLAY INVISIBLE (-27 3200);
FORCEPROP 1 LAST HDL_TAP TRUE
J 0
(475 3075);
DISPLAY 0.872340 (475 3075);
PAINT ORANGE (475 3075);
DISPLAY INVISIBLE (475 3075);
FORCEPROP 1 LAST BODY_TYPE PLUMBING
J 0
(150 3250);
DISPLAY 0.872340 (150 3250);
PAINT GREEN (150 3250);
DISPLAY INVISIBLE (150 3250);
FORCEPROP 2 LAST CDS_LIB mstr_standard
J 0
(-25 3200);
PAINT MONO (-25 3200);
DISPLAY INVISIBLE (-25 3200);
FORCEADD OFFPAGE..2
(875 3075);
FORCEPROP 2 LAST $XR0 31 
J 0
(1064 3075);
DISPLAY 0.638298 (1064 3075);
PAINT MONO (1064 3075);
FORCEPROP 2 LAST PATH I45
J 0
(1075 3125);
DISPLAY 1.021277 (1075 3125);
PAINT ORANGE (1075 3125);
DISPLAY INVISIBLE (1075 3125);
FORCEPROP 1 LAST COMMENT_BODY TRUE
J 0
(830 2980);
DISPLAY 0.872340 (830 2980);
PAINT GREEN (830 2980);
DISPLAY INVISIBLE (830 2980);
FORCEPROP 1 LAST OFFPAGE TRUE
J 0
(1200 2950);
DISPLAY 0.872340 (1200 2950);
PAINT GREEN (1200 2950);
DISPLAY INVISIBLE (1200 2950);
FORCEPROP 2 LAST CDS_LIB mstr_standard
J 0
(875 3075);
PAINT MONO (875 3075);
DISPLAY INVISIBLE (875 3075);
FORCEADD OFFPAGE..2
(875 3150);
FORCEPROP 2 LAST $XR0 31 
J 0
(1064 3150);
DISPLAY 0.638298 (1064 3150);
PAINT MONO (1064 3150);
FORCEPROP 2 LAST PATH I46
J 0
(1075 3200);
DISPLAY 1.021277 (1075 3200);
PAINT ORANGE (1075 3200);
DISPLAY INVISIBLE (1075 3200);
FORCEPROP 1 LAST COMMENT_BODY TRUE
J 0
(830 3055);
DISPLAY 0.872340 (830 3055);
PAINT GREEN (830 3055);
DISPLAY INVISIBLE (830 3055);
FORCEPROP 1 LAST OFFPAGE TRUE
J 0
(1200 3025);
DISPLAY 0.872340 (1200 3025);
PAINT GREEN (1200 3025);
DISPLAY INVISIBLE (1200 3025);
FORCEPROP 2 LAST CDS_LIB mstr_standard
J 0
(875 3150);
PAINT MONO (875 3150);
DISPLAY INVISIBLE (875 3150);
FORCEADD TAP..1
R 2
(-2275 3450);
FORCEPROP 3 LASTPIN (-2225 3450) SIG_NAME P3E_CPU0_PE1_SS_C_TXP<1>
J 0
(-2215 3460);
DISPLAY 0.659574 (-2215 3460);
PAINT MONO (-2215 3460);
DISPLAY INVISIBLE (-2215 3460);
FORCEPROP 1 LASTPIN (-2225 3450) BN 1
J 2
(-2213 3458);
DISPLAY 0.617021 (-2213 3458);
PAINT GREEN (-2213 3458);
FORCEPROP 1 LAST PATH I47
J 2
(-2273 3450);
DISPLAY 0.872340 (-2273 3450);
PAINT GREEN (-2273 3450);
DISPLAY INVISIBLE (-2273 3450);
FORCEPROP 1 LAST HDL_TAP TRUE
J 2
(-2600 3325);
DISPLAY 0.872340 (-2600 3325);
PAINT ORANGE (-2600 3325);
DISPLAY INVISIBLE (-2600 3325);
FORCEPROP 1 LAST BODY_TYPE PLUMBING
J 2
(-2275 3500);
DISPLAY 0.872340 (-2275 3500);
PAINT GREEN (-2275 3500);
DISPLAY INVISIBLE (-2275 3500);
FORCEPROP 2 LAST CDS_LIB mstr_standard
J 0
(-2275 3450);
PAINT MONO (-2275 3450);
DISPLAY INVISIBLE (-2275 3450);
FORCEADD TAP..1
R 2
(-2275 3550);
FORCEPROP 3 LASTPIN (-2225 3550) SIG_NAME P3E_CPU0_PE1_SS_C_TXP<2>
J 0
(-2215 3560);
DISPLAY 0.659574 (-2215 3560);
PAINT MONO (-2215 3560);
DISPLAY INVISIBLE (-2215 3560);
FORCEPROP 1 LASTPIN (-2225 3550) BN 2
J 2
(-2213 3558);
DISPLAY 0.617021 (-2213 3558);
PAINT GREEN (-2213 3558);
FORCEPROP 1 LAST PATH I48
J 2
(-2273 3550);
DISPLAY 0.872340 (-2273 3550);
PAINT GREEN (-2273 3550);
DISPLAY INVISIBLE (-2273 3550);
FORCEPROP 1 LAST HDL_TAP TRUE
J 2
(-2600 3425);
DISPLAY 0.872340 (-2600 3425);
PAINT ORANGE (-2600 3425);
DISPLAY INVISIBLE (-2600 3425);
FORCEPROP 1 LAST BODY_TYPE PLUMBING
J 2
(-2275 3600);
DISPLAY 0.872340 (-2275 3600);
PAINT GREEN (-2275 3600);
DISPLAY INVISIBLE (-2275 3600);
FORCEPROP 2 LAST CDS_LIB mstr_standard
J 0
(-2275 3550);
PAINT MONO (-2275 3550);
DISPLAY INVISIBLE (-2275 3550);
FORCEADD TAP..1
R 2
(-2275 3900);
FORCEPROP 3 LASTPIN (-2225 3900) SIG_NAME P3E_CPU0_PE1_SS_C_TXP<4>
J 0
(-2215 3910);
DISPLAY 0.659574 (-2215 3910);
PAINT MONO (-2215 3910);
DISPLAY INVISIBLE (-2215 3910);
FORCEPROP 1 LASTPIN (-2225 3900) BN 4
J 2
(-2213 3908);
DISPLAY 0.617021 (-2213 3908);
PAINT GREEN (-2213 3908);
FORCEPROP 1 LAST PATH I49
J 2
(-2273 3900);
DISPLAY 0.872340 (-2273 3900);
PAINT GREEN (-2273 3900);
DISPLAY INVISIBLE (-2273 3900);
FORCEPROP 1 LAST HDL_TAP TRUE
J 2
(-2600 3775);
DISPLAY 0.872340 (-2600 3775);
PAINT ORANGE (-2600 3775);
DISPLAY INVISIBLE (-2600 3775);
FORCEPROP 1 LAST BODY_TYPE PLUMBING
J 2
(-2275 3950);
DISPLAY 0.872340 (-2275 3950);
PAINT GREEN (-2275 3950);
DISPLAY INVISIBLE (-2275 3950);
FORCEPROP 2 LAST CDS_LIB mstr_standard
J 0
(-2275 3900);
PAINT MONO (-2275 3900);
DISPLAY INVISIBLE (-2275 3900);
FORCEADD OFFPAGE..1
(-3450 4500);
FORCEPROP 2 LAST $XR0 107 
J 0
(-3702 4500);
DISPLAY 0.638298 (-3702 4500);
PAINT MONO (-3702 4500);
FORCEPROP 2 LAST PATH I5
J 0
(-3700 4550);
DISPLAY 1.021277 (-3700 4550);
PAINT ORANGE (-3700 4550);
DISPLAY INVISIBLE (-3700 4550);
FORCEPROP 1 LAST COMMENT_BODY TRUE
J 0
(-3325 4400);
DISPLAY 0.872340 (-3325 4400);
PAINT GREEN (-3325 4400);
DISPLAY INVISIBLE (-3325 4400);
FORCEPROP 1 LAST OFFPAGE TRUE
J 0
(-3125 4375);
DISPLAY 0.872340 (-3125 4375);
PAINT GREEN (-3125 4375);
DISPLAY INVISIBLE (-3125 4375);
FORCEPROP 2 LAST CDS_LIB mstr_standard
J 0
(-3450 4500);
PAINT MONO (-3450 4500);
DISPLAY INVISIBLE (-3450 4500);
FORCEADD TAP..1
R 2
(-2275 3700);
FORCEPROP 3 LASTPIN (-2225 3700) SIG_NAME P3E_CPU0_PE1_SS_C_TXP<3>
J 0
(-2215 3710);
DISPLAY 0.659574 (-2215 3710);
PAINT MONO (-2215 3710);
DISPLAY INVISIBLE (-2215 3710);
FORCEPROP 1 LASTPIN (-2225 3700) BN 3
J 2
(-2213 3708);
DISPLAY 0.617021 (-2213 3708);
PAINT GREEN (-2213 3708);
FORCEPROP 1 LAST PATH I50
J 2
(-2273 3700);
DISPLAY 0.872340 (-2273 3700);
PAINT GREEN (-2273 3700);
DISPLAY INVISIBLE (-2273 3700);
FORCEPROP 1 LAST HDL_TAP TRUE
J 2
(-2600 3575);
DISPLAY 0.872340 (-2600 3575);
PAINT ORANGE (-2600 3575);
DISPLAY INVISIBLE (-2600 3575);
FORCEPROP 1 LAST BODY_TYPE PLUMBING
J 2
(-2275 3750);
DISPLAY 0.872340 (-2275 3750);
PAINT GREEN (-2275 3750);
DISPLAY INVISIBLE (-2275 3750);
FORCEPROP 2 LAST CDS_LIB mstr_standard
J 0
(-2275 3700);
PAINT MONO (-2275 3700);
DISPLAY INVISIBLE (-2275 3700);
FORCEADD TAP..1
R 2
(-2275 4000);
FORCEPROP 3 LASTPIN (-2225 4000) SIG_NAME P3E_CPU0_PE1_SS_C_TXP<5>
J 0
(-2215 4010);
DISPLAY 0.659574 (-2215 4010);
PAINT MONO (-2215 4010);
DISPLAY INVISIBLE (-2215 4010);
FORCEPROP 1 LASTPIN (-2225 4000) BN 5
J 2
(-2213 4008);
DISPLAY 0.617021 (-2213 4008);
PAINT GREEN (-2213 4008);
FORCEPROP 1 LAST PATH I51
J 2
(-2273 4000);
DISPLAY 0.872340 (-2273 4000);
PAINT GREEN (-2273 4000);
DISPLAY INVISIBLE (-2273 4000);
FORCEPROP 1 LAST HDL_TAP TRUE
J 2
(-2600 3875);
DISPLAY 0.872340 (-2600 3875);
PAINT ORANGE (-2600 3875);
DISPLAY INVISIBLE (-2600 3875);
FORCEPROP 1 LAST BODY_TYPE PLUMBING
J 2
(-2275 4050);
DISPLAY 0.872340 (-2275 4050);
PAINT GREEN (-2275 4050);
DISPLAY INVISIBLE (-2275 4050);
FORCEPROP 2 LAST CDS_LIB mstr_standard
J 0
(-2275 4000);
PAINT MONO (-2275 4000);
DISPLAY INVISIBLE (-2275 4000);
FORCEADD TAP..1
R 2
(-2275 4150);
FORCEPROP 3 LASTPIN (-2225 4150) SIG_NAME P3E_CPU0_PE1_SS_C_TXP<6>
J 0
(-2215 4160);
DISPLAY 0.659574 (-2215 4160);
PAINT MONO (-2215 4160);
DISPLAY INVISIBLE (-2215 4160);
FORCEPROP 1 LASTPIN (-2225 4150) BN 6
J 2
(-2213 4158);
DISPLAY 0.617021 (-2213 4158);
PAINT GREEN (-2213 4158);
FORCEPROP 1 LAST PATH I52
J 2
(-2273 4150);
DISPLAY 0.872340 (-2273 4150);
PAINT GREEN (-2273 4150);
DISPLAY INVISIBLE (-2273 4150);
FORCEPROP 1 LAST HDL_TAP TRUE
J 2
(-2600 4025);
DISPLAY 0.872340 (-2600 4025);
PAINT ORANGE (-2600 4025);
DISPLAY INVISIBLE (-2600 4025);
FORCEPROP 1 LAST BODY_TYPE PLUMBING
J 2
(-2275 4200);
DISPLAY 0.872340 (-2275 4200);
PAINT GREEN (-2275 4200);
DISPLAY INVISIBLE (-2275 4200);
FORCEPROP 2 LAST CDS_LIB mstr_standard
J 0
(-2275 4150);
PAINT MONO (-2275 4150);
DISPLAY INVISIBLE (-2275 4150);
FORCEADD TAP..1
R 2
(-2275 4300);
FORCEPROP 3 LASTPIN (-2225 4300) SIG_NAME P3E_CPU0_PE1_SS_C_TXP<7>
J 0
(-2215 4310);
DISPLAY 0.659574 (-2215 4310);
PAINT MONO (-2215 4310);
DISPLAY INVISIBLE (-2215 4310);
FORCEPROP 1 LASTPIN (-2225 4300) BN 7
J 2
(-2213 4308);
DISPLAY 0.617021 (-2213 4308);
PAINT GREEN (-2213 4308);
FORCEPROP 1 LAST PATH I53
J 2
(-2273 4300);
DISPLAY 0.872340 (-2273 4300);
PAINT GREEN (-2273 4300);
DISPLAY INVISIBLE (-2273 4300);
FORCEPROP 1 LAST HDL_TAP TRUE
J 2
(-2600 4175);
DISPLAY 0.872340 (-2600 4175);
PAINT ORANGE (-2600 4175);
DISPLAY INVISIBLE (-2600 4175);
FORCEPROP 1 LAST BODY_TYPE PLUMBING
J 2
(-2275 4350);
DISPLAY 0.872340 (-2275 4350);
PAINT GREEN (-2275 4350);
DISPLAY INVISIBLE (-2275 4350);
FORCEPROP 2 LAST CDS_LIB mstr_standard
J 2
(-2275 4300);
PAINT ORANGE (-2275 4300);
DISPLAY INVISIBLE (-2275 4300);
FORCEADD TAP..1
R 2
(-2025 3600);
FORCEPROP 3 LASTPIN (-1975 3600) SIG_NAME P3E_CPU0_PE1_SS_C_TXN<2>
J 0
(-1965 3610);
DISPLAY 0.659574 (-1965 3610);
PAINT MONO (-1965 3610);
DISPLAY INVISIBLE (-1965 3610);
FORCEPROP 1 LASTPIN (-1975 3600) BN 2
J 2
(-1963 3608);
DISPLAY 0.617021 (-1963 3608);
PAINT GREEN (-1963 3608);
FORCEPROP 1 LAST PATH I54
J 2
(-2023 3600);
DISPLAY 0.872340 (-2023 3600);
PAINT GREEN (-2023 3600);
DISPLAY INVISIBLE (-2023 3600);
FORCEPROP 1 LAST HDL_TAP TRUE
J 2
(-2350 3475);
DISPLAY 0.872340 (-2350 3475);
PAINT ORANGE (-2350 3475);
DISPLAY INVISIBLE (-2350 3475);
FORCEPROP 1 LAST BODY_TYPE PLUMBING
J 2
(-2025 3650);
DISPLAY 0.872340 (-2025 3650);
PAINT GREEN (-2025 3650);
DISPLAY INVISIBLE (-2025 3650);
FORCEPROP 2 LAST CDS_LIB mstr_standard
J 0
(-2025 3600);
PAINT MONO (-2025 3600);
DISPLAY INVISIBLE (-2025 3600);
FORCEADD TAP..1
R 2
(-2025 3750);
FORCEPROP 3 LASTPIN (-1975 3750) SIG_NAME P3E_CPU0_PE1_SS_C_TXN<3>
J 0
(-1965 3760);
DISPLAY 0.659574 (-1965 3760);
PAINT MONO (-1965 3760);
DISPLAY INVISIBLE (-1965 3760);
FORCEPROP 1 LASTPIN (-1975 3750) BN 3
J 2
(-1963 3758);
DISPLAY 0.617021 (-1963 3758);
PAINT GREEN (-1963 3758);
FORCEPROP 1 LAST PATH I55
J 2
(-2023 3750);
DISPLAY 0.872340 (-2023 3750);
PAINT GREEN (-2023 3750);
DISPLAY INVISIBLE (-2023 3750);
FORCEPROP 1 LAST HDL_TAP TRUE
J 2
(-2350 3625);
DISPLAY 0.872340 (-2350 3625);
PAINT ORANGE (-2350 3625);
DISPLAY INVISIBLE (-2350 3625);
FORCEPROP 1 LAST BODY_TYPE PLUMBING
J 2
(-2025 3800);
DISPLAY 0.872340 (-2025 3800);
PAINT GREEN (-2025 3800);
DISPLAY INVISIBLE (-2025 3800);
FORCEPROP 2 LAST CDS_LIB mstr_standard
J 0
(-2025 3750);
PAINT MONO (-2025 3750);
DISPLAY INVISIBLE (-2025 3750);
FORCEADD TAP..1
R 2
(-2025 3850);
FORCEPROP 3 LASTPIN (-1975 3850) SIG_NAME P3E_CPU0_PE1_SS_C_TXN<4>
J 0
(-1965 3860);
DISPLAY 0.659574 (-1965 3860);
PAINT MONO (-1965 3860);
DISPLAY INVISIBLE (-1965 3860);
FORCEPROP 1 LASTPIN (-1975 3850) BN 4
J 2
(-1963 3858);
DISPLAY 0.617021 (-1963 3858);
PAINT GREEN (-1963 3858);
FORCEPROP 1 LAST PATH I56
J 2
(-2023 3850);
DISPLAY 0.872340 (-2023 3850);
PAINT GREEN (-2023 3850);
DISPLAY INVISIBLE (-2023 3850);
FORCEPROP 1 LAST HDL_TAP TRUE
J 2
(-2350 3725);
DISPLAY 0.872340 (-2350 3725);
PAINT ORANGE (-2350 3725);
DISPLAY INVISIBLE (-2350 3725);
FORCEPROP 1 LAST BODY_TYPE PLUMBING
J 2
(-2025 3900);
DISPLAY 0.872340 (-2025 3900);
PAINT GREEN (-2025 3900);
DISPLAY INVISIBLE (-2025 3900);
FORCEPROP 2 LAST CDS_LIB mstr_standard
J 0
(-2025 3850);
PAINT MONO (-2025 3850);
DISPLAY INVISIBLE (-2025 3850);
FORCEADD TAP..1
R 2
(-2025 4050);
FORCEPROP 3 LASTPIN (-1975 4050) SIG_NAME P3E_CPU0_PE1_SS_C_TXN<5>
J 0
(-1965 4060);
DISPLAY 0.659574 (-1965 4060);
PAINT MONO (-1965 4060);
DISPLAY INVISIBLE (-1965 4060);
FORCEPROP 1 LASTPIN (-1975 4050) BN 5
J 2
(-1963 4058);
DISPLAY 0.617021 (-1963 4058);
PAINT GREEN (-1963 4058);
FORCEPROP 1 LAST PATH I57
J 2
(-2023 4050);
DISPLAY 0.872340 (-2023 4050);
PAINT GREEN (-2023 4050);
DISPLAY INVISIBLE (-2023 4050);
FORCEPROP 1 LAST HDL_TAP TRUE
J 2
(-2350 3925);
DISPLAY 0.872340 (-2350 3925);
PAINT ORANGE (-2350 3925);
DISPLAY INVISIBLE (-2350 3925);
FORCEPROP 1 LAST BODY_TYPE PLUMBING
J 2
(-2025 4100);
DISPLAY 0.872340 (-2025 4100);
PAINT GREEN (-2025 4100);
DISPLAY INVISIBLE (-2025 4100);
FORCEPROP 2 LAST CDS_LIB mstr_standard
J 0
(-2025 4050);
PAINT MONO (-2025 4050);
DISPLAY INVISIBLE (-2025 4050);
FORCEADD TAP..1
R 2
(-2025 4200);
FORCEPROP 3 LASTPIN (-1975 4200) SIG_NAME P3E_CPU0_PE1_SS_C_TXN<6>
J 0
(-1965 4210);
DISPLAY 0.659574 (-1965 4210);
PAINT MONO (-1965 4210);
DISPLAY INVISIBLE (-1965 4210);
FORCEPROP 1 LASTPIN (-1975 4200) BN 6
J 2
(-1963 4208);
DISPLAY 0.617021 (-1963 4208);
PAINT GREEN (-1963 4208);
FORCEPROP 1 LAST PATH I58
J 2
(-2023 4200);
DISPLAY 0.872340 (-2023 4200);
PAINT GREEN (-2023 4200);
DISPLAY INVISIBLE (-2023 4200);
FORCEPROP 1 LAST HDL_TAP TRUE
J 2
(-2350 4075);
DISPLAY 0.872340 (-2350 4075);
PAINT ORANGE (-2350 4075);
DISPLAY INVISIBLE (-2350 4075);
FORCEPROP 1 LAST BODY_TYPE PLUMBING
J 2
(-2025 4250);
DISPLAY 0.872340 (-2025 4250);
PAINT GREEN (-2025 4250);
DISPLAY INVISIBLE (-2025 4250);
FORCEPROP 2 LAST CDS_LIB mstr_standard
J 0
(-2025 4200);
PAINT MONO (-2025 4200);
DISPLAY INVISIBLE (-2025 4200);
FORCEADD TAP..1
R 2
(-2025 4350);
FORCEPROP 3 LASTPIN (-1975 4350) SIG_NAME P3E_CPU0_PE1_SS_C_TXN<7>
J 0
(-1965 4360);
DISPLAY 0.659574 (-1965 4360);
PAINT MONO (-1965 4360);
DISPLAY INVISIBLE (-1965 4360);
FORCEPROP 1 LASTPIN (-1975 4350) BN 7
J 2
(-1963 4358);
DISPLAY 0.617021 (-1963 4358);
PAINT GREEN (-1963 4358);
FORCEPROP 1 LAST PATH I59
J 2
(-2023 4350);
DISPLAY 0.872340 (-2023 4350);
PAINT GREEN (-2023 4350);
DISPLAY INVISIBLE (-2023 4350);
FORCEPROP 1 LAST HDL_TAP TRUE
J 2
(-2350 4225);
DISPLAY 0.872340 (-2350 4225);
PAINT ORANGE (-2350 4225);
DISPLAY INVISIBLE (-2350 4225);
FORCEPROP 1 LAST BODY_TYPE PLUMBING
J 2
(-2025 4400);
DISPLAY 0.872340 (-2025 4400);
PAINT GREEN (-2025 4400);
DISPLAY INVISIBLE (-2025 4400);
FORCEPROP 2 LAST CDS_LIB mstr_standard
J 2
(-2025 4350);
PAINT ORANGE (-2025 4350);
DISPLAY INVISIBLE (-2025 4350);
FORCEADD TAP..1
R 2
(-2275 2100);
FORCEPROP 3 LASTPIN (-2225 2100) SIG_NAME P3E_CPU0_PE2_SS_C_TXN<7>
J 0
(-2215 2110);
DISPLAY 0.659574 (-2215 2110);
PAINT MONO (-2215 2110);
DISPLAY INVISIBLE (-2215 2110);
FORCEPROP 1 LASTPIN (-2225 2100) BN 7
J 2
(-2213 2108);
DISPLAY 0.617021 (-2213 2108);
PAINT GREEN (-2213 2108);
FORCEPROP 1 LAST PATH I6
J 2
(-2273 2100);
DISPLAY 0.872340 (-2273 2100);
PAINT GREEN (-2273 2100);
DISPLAY INVISIBLE (-2273 2100);
FORCEPROP 1 LAST HDL_TAP TRUE
J 2
(-2600 1975);
DISPLAY 0.872340 (-2600 1975);
PAINT ORANGE (-2600 1975);
DISPLAY INVISIBLE (-2600 1975);
FORCEPROP 1 LAST BODY_TYPE PLUMBING
J 2
(-2275 2150);
DISPLAY 0.872340 (-2275 2150);
PAINT GREEN (-2275 2150);
DISPLAY INVISIBLE (-2275 2150);
FORCEPROP 2 LAST CDS_LIB mstr_standard
J 0
(-2275 2100);
PAINT MONO (-2275 2100);
DISPLAY INVISIBLE (-2275 2100);
FORCEADD TAP..1
(-250 3500);
FORCEPROP 3 LASTPIN (-300 3500) SIG_NAME P3E_CPU0_PE1_SS_R_RXN<2>
J 0
(-290 3510);
DISPLAY 0.659574 (-290 3510);
PAINT MONO (-290 3510);
DISPLAY INVISIBLE (-290 3510);
FORCEPROP 1 LASTPIN (-300 3500) BN 2
J 0
(-312 3508);
DISPLAY 0.617021 (-312 3508);
PAINT GREEN (-312 3508);
FORCEPROP 1 LAST PATH I60
J 0
(-252 3500);
DISPLAY 0.872340 (-252 3500);
PAINT GREEN (-252 3500);
DISPLAY INVISIBLE (-252 3500);
FORCEPROP 1 LAST HDL_TAP TRUE
J 0
(250 3375);
DISPLAY 0.872340 (250 3375);
PAINT ORANGE (250 3375);
DISPLAY INVISIBLE (250 3375);
FORCEPROP 1 LAST BODY_TYPE PLUMBING
J 0
(-75 3550);
DISPLAY 0.872340 (-75 3550);
PAINT GREEN (-75 3550);
DISPLAY INVISIBLE (-75 3550);
FORCEPROP 2 LAST CDS_LIB mstr_standard
J 0
(-250 3500);
PAINT MONO (-250 3500);
DISPLAY INVISIBLE (-250 3500);
FORCEADD TAP..1
(-250 3700);
FORCEPROP 3 LASTPIN (-300 3700) SIG_NAME P3E_CPU0_PE1_SS_R_RXN<3>
J 0
(-290 3710);
DISPLAY 0.659574 (-290 3710);
PAINT MONO (-290 3710);
DISPLAY INVISIBLE (-290 3710);
FORCEPROP 1 LASTPIN (-300 3700) BN 3
J 0
(-312 3708);
DISPLAY 0.617021 (-312 3708);
PAINT GREEN (-312 3708);
FORCEPROP 1 LAST PATH I61
J 0
(-252 3700);
DISPLAY 0.872340 (-252 3700);
PAINT GREEN (-252 3700);
DISPLAY INVISIBLE (-252 3700);
FORCEPROP 1 LAST HDL_TAP TRUE
J 0
(250 3575);
DISPLAY 0.872340 (250 3575);
PAINT ORANGE (250 3575);
DISPLAY INVISIBLE (250 3575);
FORCEPROP 1 LAST BODY_TYPE PLUMBING
J 0
(-75 3750);
DISPLAY 0.872340 (-75 3750);
PAINT GREEN (-75 3750);
DISPLAY INVISIBLE (-75 3750);
FORCEPROP 2 LAST CDS_LIB mstr_standard
J 0
(-250 3700);
PAINT MONO (-250 3700);
DISPLAY INVISIBLE (-250 3700);
FORCEADD TAP..1
(-250 3850);
FORCEPROP 3 LASTPIN (-300 3850) SIG_NAME P3E_CPU0_PE1_SS_R_RXN<4>
J 0
(-290 3860);
DISPLAY 0.659574 (-290 3860);
PAINT MONO (-290 3860);
DISPLAY INVISIBLE (-290 3860);
FORCEPROP 1 LASTPIN (-300 3850) BN 4
J 0
(-312 3858);
DISPLAY 0.617021 (-312 3858);
PAINT GREEN (-312 3858);
FORCEPROP 1 LAST PATH I62
J 0
(-252 3850);
DISPLAY 0.872340 (-252 3850);
PAINT GREEN (-252 3850);
DISPLAY INVISIBLE (-252 3850);
FORCEPROP 1 LAST HDL_TAP TRUE
J 0
(250 3725);
DISPLAY 0.872340 (250 3725);
PAINT ORANGE (250 3725);
DISPLAY INVISIBLE (250 3725);
FORCEPROP 1 LAST BODY_TYPE PLUMBING
J 0
(-75 3900);
DISPLAY 0.872340 (-75 3900);
PAINT GREEN (-75 3900);
DISPLAY INVISIBLE (-75 3900);
FORCEPROP 2 LAST CDS_LIB mstr_standard
J 0
(-250 3850);
PAINT MONO (-250 3850);
DISPLAY INVISIBLE (-250 3850);
FORCEADD TAP..1
(-250 4000);
FORCEPROP 3 LASTPIN (-300 4000) SIG_NAME P3E_CPU0_PE1_SS_R_RXN<5>
J 0
(-290 4010);
DISPLAY 0.659574 (-290 4010);
PAINT MONO (-290 4010);
DISPLAY INVISIBLE (-290 4010);
FORCEPROP 1 LASTPIN (-300 4000) BN 5
J 0
(-312 4008);
DISPLAY 0.617021 (-312 4008);
PAINT GREEN (-312 4008);
FORCEPROP 1 LAST PATH I63
J 0
(-252 4000);
DISPLAY 0.872340 (-252 4000);
PAINT GREEN (-252 4000);
DISPLAY INVISIBLE (-252 4000);
FORCEPROP 1 LAST HDL_TAP TRUE
J 0
(250 3875);
DISPLAY 0.872340 (250 3875);
PAINT ORANGE (250 3875);
DISPLAY INVISIBLE (250 3875);
FORCEPROP 1 LAST BODY_TYPE PLUMBING
J 0
(-75 4050);
DISPLAY 0.872340 (-75 4050);
PAINT GREEN (-75 4050);
DISPLAY INVISIBLE (-75 4050);
FORCEPROP 2 LAST CDS_LIB mstr_standard
J 0
(-250 4000);
PAINT MONO (-250 4000);
DISPLAY INVISIBLE (-250 4000);
FORCEADD TAP..1
(-250 4150);
FORCEPROP 3 LASTPIN (-300 4150) SIG_NAME P3E_CPU0_PE1_SS_R_RXN<6>
J 0
(-290 4160);
DISPLAY 0.659574 (-290 4160);
PAINT MONO (-290 4160);
DISPLAY INVISIBLE (-290 4160);
FORCEPROP 1 LASTPIN (-300 4150) BN 6
J 0
(-312 4158);
DISPLAY 0.617021 (-312 4158);
PAINT GREEN (-312 4158);
FORCEPROP 1 LAST PATH I64
J 0
(-252 4150);
DISPLAY 0.872340 (-252 4150);
PAINT GREEN (-252 4150);
DISPLAY INVISIBLE (-252 4150);
FORCEPROP 1 LAST HDL_TAP TRUE
J 0
(250 4025);
DISPLAY 0.872340 (250 4025);
PAINT ORANGE (250 4025);
DISPLAY INVISIBLE (250 4025);
FORCEPROP 1 LAST BODY_TYPE PLUMBING
J 0
(-75 4200);
DISPLAY 0.872340 (-75 4200);
PAINT GREEN (-75 4200);
DISPLAY INVISIBLE (-75 4200);
FORCEPROP 2 LAST CDS_LIB mstr_standard
J 0
(-250 4150);
PAINT MONO (-250 4150);
DISPLAY INVISIBLE (-250 4150);
FORCEADD TAP..1
(-250 4300);
FORCEPROP 3 LASTPIN (-300 4300) SIG_NAME P3E_CPU0_PE1_SS_R_RXN<7>
J 0
(-290 4310);
DISPLAY 0.659574 (-290 4310);
PAINT MONO (-290 4310);
DISPLAY INVISIBLE (-290 4310);
FORCEPROP 1 LASTPIN (-300 4300) BN 7
J 0
(-312 4308);
DISPLAY 0.617021 (-312 4308);
PAINT GREEN (-312 4308);
FORCEPROP 1 LAST PATH I65
J 0
(-252 4300);
DISPLAY 0.872340 (-252 4300);
PAINT GREEN (-252 4300);
DISPLAY INVISIBLE (-252 4300);
FORCEPROP 1 LAST HDL_TAP TRUE
J 0
(250 4175);
DISPLAY 0.872340 (250 4175);
PAINT ORANGE (250 4175);
DISPLAY INVISIBLE (250 4175);
FORCEPROP 1 LAST BODY_TYPE PLUMBING
J 0
(-75 4350);
DISPLAY 0.872340 (-75 4350);
PAINT GREEN (-75 4350);
DISPLAY INVISIBLE (-75 4350);
FORCEPROP 2 LAST CDS_LIB mstr_standard
J 0
(-250 4300);
PAINT MONO (-250 4300);
DISPLAY INVISIBLE (-250 4300);
FORCEADD TAP..1
(-250 4400);
FORCEPROP 3 LASTPIN (-300 4400) SIG_NAME P3E_CPU0_PE1_PCH_CON_RXP<8>
J 0
(-290 4410);
DISPLAY 0.659574 (-290 4410);
PAINT MONO (-290 4410);
DISPLAY INVISIBLE (-290 4410);
FORCEPROP 1 LASTPIN (-300 4400) BN 8
J 0
(-312 4408);
DISPLAY 0.617021 (-312 4408);
PAINT GREEN (-312 4408);
FORCEPROP 1 LAST PATH I66
J 0
(-252 4400);
DISPLAY 0.872340 (-252 4400);
PAINT GREEN (-252 4400);
DISPLAY INVISIBLE (-252 4400);
FORCEPROP 1 LAST HDL_TAP TRUE
J 0
(250 4275);
DISPLAY 0.872340 (250 4275);
PAINT ORANGE (250 4275);
DISPLAY INVISIBLE (250 4275);
FORCEPROP 1 LAST BODY_TYPE PLUMBING
J 0
(-75 4450);
DISPLAY 0.872340 (-75 4450);
PAINT GREEN (-75 4450);
DISPLAY INVISIBLE (-75 4450);
FORCEPROP 2 LAST CDS_LIB mstr_standard
J 0
(-250 4400);
PAINT ORANGE (-250 4400);
DISPLAY INVISIBLE (-250 4400);
FORCEADD TAP..1
(-25 3650);
FORCEPROP 3 LASTPIN (-75 3650) SIG_NAME P3E_CPU0_PE1_SS_R_RXP<3>
J 0
(-65 3660);
DISPLAY 0.659574 (-65 3660);
PAINT MONO (-65 3660);
DISPLAY INVISIBLE (-65 3660);
FORCEPROP 1 LASTPIN (-75 3650) BN 3
J 0
(-87 3658);
DISPLAY 0.617021 (-87 3658);
PAINT GREEN (-87 3658);
FORCEPROP 1 LAST PATH I67
J 0
(-27 3650);
DISPLAY 0.872340 (-27 3650);
PAINT GREEN (-27 3650);
DISPLAY INVISIBLE (-27 3650);
FORCEPROP 1 LAST HDL_TAP TRUE
J 0
(475 3525);
DISPLAY 0.872340 (475 3525);
PAINT ORANGE (475 3525);
DISPLAY INVISIBLE (475 3525);
FORCEPROP 1 LAST BODY_TYPE PLUMBING
J 0
(150 3700);
DISPLAY 0.872340 (150 3700);
PAINT GREEN (150 3700);
DISPLAY INVISIBLE (150 3700);
FORCEPROP 2 LAST CDS_LIB mstr_standard
J 0
(-25 3650);
PAINT MONO (-25 3650);
DISPLAY INVISIBLE (-25 3650);
FORCEADD TAP..1
(-25 3550);
FORCEPROP 3 LASTPIN (-75 3550) SIG_NAME P3E_CPU0_PE1_SS_R_RXP<2>
J 0
(-65 3560);
DISPLAY 0.659574 (-65 3560);
PAINT MONO (-65 3560);
DISPLAY INVISIBLE (-65 3560);
FORCEPROP 1 LASTPIN (-75 3550) BN 2
J 0
(-87 3558);
DISPLAY 0.617021 (-87 3558);
PAINT GREEN (-87 3558);
FORCEPROP 1 LAST PATH I68
J 0
(-27 3550);
DISPLAY 0.872340 (-27 3550);
PAINT GREEN (-27 3550);
DISPLAY INVISIBLE (-27 3550);
FORCEPROP 1 LAST HDL_TAP TRUE
J 0
(475 3425);
DISPLAY 0.872340 (475 3425);
PAINT ORANGE (475 3425);
DISPLAY INVISIBLE (475 3425);
FORCEPROP 1 LAST BODY_TYPE PLUMBING
J 0
(150 3600);
DISPLAY 0.872340 (150 3600);
PAINT GREEN (150 3600);
DISPLAY INVISIBLE (150 3600);
FORCEPROP 2 LAST CDS_LIB mstr_standard
J 0
(-25 3550);
PAINT MONO (-25 3550);
DISPLAY INVISIBLE (-25 3550);
FORCEADD TAP..1
(-25 3800);
FORCEPROP 3 LASTPIN (-75 3800) SIG_NAME P3E_CPU0_PE1_SS_R_RXP<4>
J 0
(-65 3810);
DISPLAY 0.659574 (-65 3810);
PAINT MONO (-65 3810);
DISPLAY INVISIBLE (-65 3810);
FORCEPROP 1 LASTPIN (-75 3800) BN 4
J 0
(-87 3808);
DISPLAY 0.617021 (-87 3808);
PAINT GREEN (-87 3808);
FORCEPROP 1 LAST PATH I69
J 0
(-27 3800);
DISPLAY 0.872340 (-27 3800);
PAINT GREEN (-27 3800);
DISPLAY INVISIBLE (-27 3800);
FORCEPROP 1 LAST HDL_TAP TRUE
J 0
(475 3675);
DISPLAY 0.872340 (475 3675);
PAINT ORANGE (475 3675);
DISPLAY INVISIBLE (475 3675);
FORCEPROP 1 LAST BODY_TYPE PLUMBING
J 0
(150 3850);
DISPLAY 0.872340 (150 3850);
PAINT GREEN (150 3850);
DISPLAY INVISIBLE (150 3850);
FORCEPROP 2 LAST CDS_LIB mstr_standard
J 0
(-25 3800);
PAINT MONO (-25 3800);
DISPLAY INVISIBLE (-25 3800);
FORCEADD TAP..1
R 2
(-2275 2250);
FORCEPROP 3 LASTPIN (-2225 2250) SIG_NAME P3E_CPU0_PE2_SS_C_TXN<6>
J 0
(-2215 2260);
DISPLAY 0.659574 (-2215 2260);
PAINT MONO (-2215 2260);
DISPLAY INVISIBLE (-2215 2260);
FORCEPROP 1 LASTPIN (-2225 2250) BN 6
J 2
(-2213 2258);
DISPLAY 0.617021 (-2213 2258);
PAINT GREEN (-2213 2258);
FORCEPROP 1 LAST PATH I7
J 2
(-2273 2250);
DISPLAY 0.872340 (-2273 2250);
PAINT GREEN (-2273 2250);
DISPLAY INVISIBLE (-2273 2250);
FORCEPROP 1 LAST HDL_TAP TRUE
J 2
(-2600 2125);
DISPLAY 0.872340 (-2600 2125);
PAINT ORANGE (-2600 2125);
DISPLAY INVISIBLE (-2600 2125);
FORCEPROP 1 LAST BODY_TYPE PLUMBING
J 2
(-2275 2300);
DISPLAY 0.872340 (-2275 2300);
PAINT GREEN (-2275 2300);
DISPLAY INVISIBLE (-2275 2300);
FORCEPROP 2 LAST CDS_LIB mstr_standard
J 0
(-2275 2250);
PAINT MONO (-2275 2250);
DISPLAY INVISIBLE (-2275 2250);
FORCEADD TAP..1
(-25 3950);
FORCEPROP 3 LASTPIN (-75 3950) SIG_NAME P3E_CPU0_PE1_SS_R_RXP<5>
J 0
(-65 3960);
DISPLAY 0.659574 (-65 3960);
PAINT MONO (-65 3960);
DISPLAY INVISIBLE (-65 3960);
FORCEPROP 1 LASTPIN (-75 3950) BN 5
J 0
(-87 3958);
DISPLAY 0.617021 (-87 3958);
PAINT GREEN (-87 3958);
FORCEPROP 1 LAST PATH I70
J 0
(-27 3950);
DISPLAY 0.872340 (-27 3950);
PAINT GREEN (-27 3950);
DISPLAY INVISIBLE (-27 3950);
FORCEPROP 1 LAST HDL_TAP TRUE
J 0
(475 3825);
DISPLAY 0.872340 (475 3825);
PAINT ORANGE (475 3825);
DISPLAY INVISIBLE (475 3825);
FORCEPROP 1 LAST BODY_TYPE PLUMBING
J 0
(150 4000);
DISPLAY 0.872340 (150 4000);
PAINT GREEN (150 4000);
DISPLAY INVISIBLE (150 4000);
FORCEPROP 2 LAST CDS_LIB mstr_standard
J 0
(-25 3950);
PAINT MONO (-25 3950);
DISPLAY INVISIBLE (-25 3950);
FORCEADD TAP..1
(-25 4100);
FORCEPROP 3 LASTPIN (-75 4100) SIG_NAME P3E_CPU0_PE1_SS_R_RXP<6>
J 0
(-65 4110);
DISPLAY 0.659574 (-65 4110);
PAINT MONO (-65 4110);
DISPLAY INVISIBLE (-65 4110);
FORCEPROP 1 LASTPIN (-75 4100) BN 6
J 0
(-87 4108);
DISPLAY 0.617021 (-87 4108);
PAINT GREEN (-87 4108);
FORCEPROP 1 LAST PATH I71
J 0
(-27 4100);
DISPLAY 0.872340 (-27 4100);
PAINT GREEN (-27 4100);
DISPLAY INVISIBLE (-27 4100);
FORCEPROP 1 LAST HDL_TAP TRUE
J 0
(475 3975);
DISPLAY 0.872340 (475 3975);
PAINT ORANGE (475 3975);
DISPLAY INVISIBLE (475 3975);
FORCEPROP 1 LAST BODY_TYPE PLUMBING
J 0
(150 4150);
DISPLAY 0.872340 (150 4150);
PAINT GREEN (150 4150);
DISPLAY INVISIBLE (150 4150);
FORCEPROP 2 LAST CDS_LIB mstr_standard
J 0
(-25 4100);
PAINT MONO (-25 4100);
DISPLAY INVISIBLE (-25 4100);
FORCEADD TAP..1
(-25 4250);
FORCEPROP 3 LASTPIN (-75 4250) SIG_NAME P3E_CPU0_PE1_SS_R_RXP<7>
J 0
(-65 4260);
DISPLAY 0.659574 (-65 4260);
PAINT MONO (-65 4260);
DISPLAY INVISIBLE (-65 4260);
FORCEPROP 1 LASTPIN (-75 4250) BN 7
J 0
(-87 4258);
DISPLAY 0.617021 (-87 4258);
PAINT GREEN (-87 4258);
FORCEPROP 1 LAST PATH I72
J 0
(-27 4250);
DISPLAY 0.872340 (-27 4250);
PAINT GREEN (-27 4250);
DISPLAY INVISIBLE (-27 4250);
FORCEPROP 1 LAST HDL_TAP TRUE
J 0
(475 4125);
DISPLAY 0.872340 (475 4125);
PAINT ORANGE (475 4125);
DISPLAY INVISIBLE (475 4125);
FORCEPROP 1 LAST BODY_TYPE PLUMBING
J 0
(150 4300);
DISPLAY 0.872340 (150 4300);
PAINT GREEN (150 4300);
DISPLAY INVISIBLE (150 4300);
FORCEPROP 2 LAST CDS_LIB mstr_standard
J 0
(-25 4250);
PAINT MONO (-25 4250);
DISPLAY INVISIBLE (-25 4250);
FORCEADD OFFPAGE..2
(875 4300);
FORCEPROP 2 LAST $XR0 107 
J 0
(1189 4300);
DISPLAY 0.638298 (1189 4300);
PAINT MONO (1189 4300);
FORCEPROP 2 LAST $XR1 ?
J 0
(1064 4300);
DISPLAY 0.638298 (1064 4300);
PAINT MONO (1064 4300);
FORCEPROP 2 LAST PATH I73
J 0
(1200 4350);
DISPLAY 1.021277 (1200 4350);
PAINT ORANGE (1200 4350);
DISPLAY INVISIBLE (1200 4350);
FORCEPROP 1 LAST COMMENT_BODY TRUE
J 0
(830 4205);
DISPLAY 0.872340 (830 4205);
PAINT GREEN (830 4205);
DISPLAY INVISIBLE (830 4205);
FORCEPROP 1 LAST OFFPAGE TRUE
J 0
(1200 4175);
DISPLAY 0.872340 (1200 4175);
PAINT GREEN (1200 4175);
DISPLAY INVISIBLE (1200 4175);
FORCEPROP 2 LAST CDS_LIB mstr_standard
J 0
(875 4300);
PAINT MONO (875 4300);
DISPLAY INVISIBLE (875 4300);
FORCEADD OFFPAGE..2
(875 4375);
FORCEPROP 2 LAST $XR0 107 
J 0
(1189 4375);
DISPLAY 0.638298 (1189 4375);
PAINT MONO (1189 4375);
FORCEPROP 2 LAST $XR1 ?
J 0
(1064 4375);
DISPLAY 0.638298 (1064 4375);
PAINT MONO (1064 4375);
FORCEPROP 2 LAST PATH I74
J 0
(1200 4425);
DISPLAY 1.021277 (1200 4425);
PAINT ORANGE (1200 4425);
DISPLAY INVISIBLE (1200 4425);
FORCEPROP 1 LAST COMMENT_BODY TRUE
J 0
(830 4280);
DISPLAY 0.872340 (830 4280);
PAINT GREEN (830 4280);
DISPLAY INVISIBLE (830 4280);
FORCEPROP 1 LAST OFFPAGE TRUE
J 0
(1200 4250);
DISPLAY 0.872340 (1200 4250);
PAINT GREEN (1200 4250);
DISPLAY INVISIBLE (1200 4250);
FORCEPROP 2 LAST CDS_LIB mstr_standard
J 0
(875 4375);
PAINT MONO (875 4375);
DISPLAY INVISIBLE (875 4375);
FORCEADD OFFPAGE..2
(875 4475);
FORCEPROP 2 LAST $XR0 108 
J 0
(1064 4475);
DISPLAY 0.638298 (1064 4475);
PAINT MONO (1064 4475);
FORCEPROP 2 LAST $XR1 244 
J 0
(1184 4475);
DISPLAY 0.638298 (1184 4475);
PAINT MONO (1184 4475);
FORCEPROP 2 LAST PATH I75
J 0
(1200 4525);
DISPLAY 1.021277 (1200 4525);
PAINT ORANGE (1200 4525);
DISPLAY INVISIBLE (1200 4525);
FORCEPROP 1 LAST COMMENT_BODY TRUE
J 0
(830 4380);
DISPLAY 0.872340 (830 4380);
PAINT GREEN (830 4380);
DISPLAY INVISIBLE (830 4380);
FORCEPROP 1 LAST OFFPAGE TRUE
J 0
(1200 4350);
DISPLAY 0.872340 (1200 4350);
PAINT GREEN (1200 4350);
DISPLAY INVISIBLE (1200 4350);
FORCEPROP 2 LAST $XRERR ?
J 0
(1064 4475);
DISPLAY 0.638298 (1064 4475);
PAINT MONO (1064 4475);
DISPLAY INVISIBLE (1064 4475);
FORCEPROP 2 LAST $XRERR ?
J 0
(1064 4475);
DISPLAY 0.638298 (1064 4475);
PAINT MONO (1064 4475);
DISPLAY INVISIBLE (1064 4475);
FORCEPROP 2 LAST CDS_LIB mstr_standard
J 0
(875 4475);
PAINT MONO (875 4475);
DISPLAY INVISIBLE (875 4475);
FORCEADD TAP..1
(-25 2600);
FORCEPROP 3 LASTPIN (-75 2600) SIG_NAME P3E_CPU0_PE2_SS_RXP<3>
J 0
(-65 2610);
DISPLAY 0.659574 (-65 2610);
PAINT MONO (-65 2610);
DISPLAY INVISIBLE (-65 2610);
FORCEPROP 1 LASTPIN (-75 2600) BN 3
J 0
(-87 2608);
DISPLAY 0.617021 (-87 2608);
PAINT GREEN (-87 2608);
FORCEPROP 1 LAST PATH I76
J 0
(-27 2600);
DISPLAY 0.872340 (-27 2600);
PAINT GREEN (-27 2600);
DISPLAY INVISIBLE (-27 2600);
FORCEPROP 1 LAST HDL_TAP TRUE
J 0
(475 2475);
DISPLAY 0.872340 (475 2475);
PAINT ORANGE (475 2475);
DISPLAY INVISIBLE (475 2475);
FORCEPROP 1 LAST BODY_TYPE PLUMBING
J 0
(150 2650);
DISPLAY 0.872340 (150 2650);
PAINT GREEN (150 2650);
DISPLAY INVISIBLE (150 2650);
FORCEPROP 2 LAST CDS_LIB mstr_standard
J 0
(-25 2600);
PAINT MONO (-25 2600);
DISPLAY INVISIBLE (-25 2600);
FORCEADD TAP..1
(-250 2950);
FORCEPROP 3 LASTPIN (-300 2950) SIG_NAME P3E_CPU0_PE2_SS_RXN<1>
J 0
(-290 2960);
DISPLAY 0.659574 (-290 2960);
PAINT MONO (-290 2960);
DISPLAY INVISIBLE (-290 2960);
FORCEPROP 1 LASTPIN (-300 2950) BN 1
J 0
(-312 2958);
DISPLAY 0.617021 (-312 2958);
PAINT GREEN (-312 2958);
FORCEPROP 1 LAST PATH I77
J 0
(-252 2950);
DISPLAY 0.872340 (-252 2950);
PAINT GREEN (-252 2950);
DISPLAY INVISIBLE (-252 2950);
FORCEPROP 1 LAST HDL_TAP TRUE
J 0
(250 2825);
DISPLAY 0.872340 (250 2825);
PAINT ORANGE (250 2825);
DISPLAY INVISIBLE (250 2825);
FORCEPROP 1 LAST BODY_TYPE PLUMBING
J 0
(-75 3000);
DISPLAY 0.872340 (-75 3000);
PAINT GREEN (-75 3000);
DISPLAY INVISIBLE (-75 3000);
FORCEPROP 2 LAST CDS_LIB mstr_standard
J 0
(-250 2950);
PAINT MONO (-250 2950);
DISPLAY INVISIBLE (-250 2950);
FORCEADD SCONN200_H68296001..2
(-975 3200);
FORCEPROP 1 LAST PART_NUMBER H68296-001
J 0
(-1275 1800);
DISPLAY 0.617021 (-1275 1800);
PAINT BLUE (-1275 1800);
FORCEPROP 2 LASTPIN (-1325 2250) $PN 187
J 2
(-1335 2260);
DISPLAY 0.617021 (-1335 2260);
PAINT ORANGE (-1335 2260);
FORCEPROP 2 LASTPIN (-625 2950) $PN 160
J 0
(-615 2960);
DISPLAY 0.617021 (-615 2960);
PAINT ORANGE (-615 2960);
FORCEPROP 2 LASTPIN (-625 3000) $PN 158
J 0
(-615 3010);
DISPLAY 0.617021 (-615 3010);
PAINT ORANGE (-615 3010);
FORCEPROP 2 LASTPIN (-625 2000) $PN 198
J 0
(-615 2010);
DISPLAY 0.617021 (-615 2010);
PAINT ORANGE (-615 2010);
FORCEPROP 2 LASTPIN (-625 2050) $PN 196
J 0
(-615 2060);
DISPLAY 0.617021 (-615 2060);
PAINT ORANGE (-615 2060);
FORCEPROP 2 LASTPIN (-625 2100) $PN 194
J 0
(-615 2110);
DISPLAY 0.617021 (-615 2110);
PAINT ORANGE (-615 2110);
FORCEPROP 2 LASTPIN (-625 2150) $PN 192
J 0
(-615 2160);
DISPLAY 0.617021 (-615 2160);
PAINT ORANGE (-615 2160);
FORCEPROP 2 LASTPIN (-625 2200) $PN 190
J 0
(-615 2210);
DISPLAY 0.617021 (-615 2210);
PAINT ORANGE (-615 2210);
FORCEPROP 2 LASTPIN (-625 2250) $PN 188
J 0
(-615 2260);
DISPLAY 0.617021 (-615 2260);
PAINT ORANGE (-615 2260);
FORCEPROP 2 LASTPIN (-625 2300) $PN 186
J 0
(-615 2310);
DISPLAY 0.617021 (-615 2310);
PAINT ORANGE (-615 2310);
FORCEPROP 2 LASTPIN (-625 2350) $PN 184
J 0
(-615 2360);
DISPLAY 0.617021 (-615 2360);
PAINT ORANGE (-615 2360);
FORCEPROP 2 LASTPIN (-625 3050) $PN 156
J 0
(-615 3060);
DISPLAY 0.617021 (-615 3060);
PAINT ORANGE (-615 3060);
FORCEPROP 2 LASTPIN (-625 3350) $PN 144
J 0
(-615 3360);
DISPLAY 0.617021 (-615 3360);
PAINT ORANGE (-615 3360);
FORCEPROP 2 LASTPIN (-1325 3100) $PN 153
J 2
(-1335 3110);
DISPLAY 0.617021 (-1335 3110);
PAINT ORANGE (-1335 3110);
FORCEPROP 2 LASTPIN (-1325 3050) $PN 155
J 2
(-1335 3060);
DISPLAY 0.617021 (-1335 3060);
PAINT ORANGE (-1335 3060);
FORCEPROP 2 LASTPIN (-1325 4400) $PN 101
J 2
(-1335 4410);
DISPLAY 0.617021 (-1335 4410);
PAINT ORANGE (-1335 4410);
FORCEPROP 2 LASTPIN (-1325 4350) $PN 103
J 2
(-1335 4360);
DISPLAY 0.617021 (-1335 4360);
PAINT ORANGE (-1335 4360);
FORCEPROP 2 LASTPIN (-1325 4300) $PN 105
J 2
(-1335 4310);
DISPLAY 0.617021 (-1335 4310);
PAINT ORANGE (-1335 4310);
FORCEPROP 2 LASTPIN (-625 3900) $PN 122
J 0
(-615 3910);
DISPLAY 0.617021 (-615 3910);
PAINT ORANGE (-615 3910);
FORCEPROP 2 LASTPIN (-1325 2550) $PN 175
J 2
(-1335 2560);
DISPLAY 0.617021 (-1335 2560);
PAINT ORANGE (-1335 2560);
FORCEPROP 2 LASTPIN (-1325 3150) $PN 151
J 2
(-1335 3160);
DISPLAY 0.617021 (-1335 3160);
PAINT ORANGE (-1335 3160);
FORCEPROP 2 LASTPIN (-1325 2600) $PN 173
J 2
(-1335 2610);
DISPLAY 0.617021 (-1335 2610);
PAINT ORANGE (-1335 2610);
FORCEPROP 2 LASTPIN (-1325 3200) $PN 149
J 2
(-1335 3210);
DISPLAY 0.617021 (-1335 3210);
PAINT ORANGE (-1335 3210);
FORCEPROP 2 LASTPIN (-1325 2850) $PN 163
J 2
(-1335 2860);
DISPLAY 0.617021 (-1335 2860);
PAINT ORANGE (-1335 2860);
FORCEPROP 2 LASTPIN (-1325 2800) $PN 165
J 2
(-1335 2810);
DISPLAY 0.617021 (-1335 2810);
PAINT ORANGE (-1335 2810);
FORCEPROP 2 LASTPIN (-1325 2750) $PN 167
J 2
(-1335 2760);
DISPLAY 0.617021 (-1335 2760);
PAINT ORANGE (-1335 2760);
FORCEPROP 2 LASTPIN (-1325 2700) $PN 169
J 2
(-1335 2710);
DISPLAY 0.617021 (-1335 2710);
PAINT ORANGE (-1335 2710);
FORCEPROP 2 LASTPIN (-625 1950) $PN 200
J 0
(-615 1960);
DISPLAY 0.617021 (-615 1960);
PAINT ORANGE (-615 1960);
FORCEPROP 2 LASTPIN (-625 3450) $PN 140
J 0
(-615 3460);
DISPLAY 0.617021 (-615 3460);
PAINT ORANGE (-615 3460);
FORCEPROP 2 LASTPIN (-625 3850) $PN 124
J 0
(-615 3860);
DISPLAY 0.617021 (-615 3860);
PAINT ORANGE (-615 3860);
FORCEPROP 2 LASTPIN (-625 3750) $PN 128
J 0
(-615 3760);
DISPLAY 0.617021 (-615 3760);
PAINT ORANGE (-615 3760);
FORCEPROP 2 LASTPIN (-625 4150) $PN 112
J 0
(-615 4160);
DISPLAY 0.617021 (-615 4160);
PAINT ORANGE (-615 4160);
FORCEPROP 2 LASTPIN (-625 4250) $PN 108
J 0
(-615 4260);
DISPLAY 0.617021 (-615 4260);
PAINT ORANGE (-615 4260);
FORCEPROP 2 LASTPIN (-625 4300) $PN 106
J 0
(-615 4310);
DISPLAY 0.617021 (-615 4310);
PAINT ORANGE (-615 4310);
FORCEPROP 2 LASTPIN (-1325 2450) $PN 179
J 2
(-1335 2460);
DISPLAY 0.617021 (-1335 2460);
PAINT ORANGE (-1335 2460);
FORCEPROP 2 LASTPIN (-1325 2500) $PN 177
J 2
(-1335 2510);
DISPLAY 0.617021 (-1335 2510);
PAINT ORANGE (-1335 2510);
FORCEPROP 2 LASTPIN (-1325 2400) $PN 181
J 2
(-1335 2410);
DISPLAY 0.617021 (-1335 2410);
PAINT ORANGE (-1335 2410);
FORCEPROP 2 LASTPIN (-1325 2350) $PN 183
J 2
(-1335 2360);
DISPLAY 0.617021 (-1335 2360);
PAINT ORANGE (-1335 2360);
FORCEPROP 2 LASTPIN (-1325 2300) $PN 185
J 2
(-1335 2310);
DISPLAY 0.617021 (-1335 2310);
PAINT ORANGE (-1335 2310);
FORCEPROP 2 LASTPIN (-1325 2050) $PN 195
J 2
(-1335 2060);
DISPLAY 0.617021 (-1335 2060);
PAINT ORANGE (-1335 2060);
FORCEPROP 2 LASTPIN (-1325 2000) $PN 197
J 2
(-1335 2010);
DISPLAY 0.617021 (-1335 2010);
PAINT ORANGE (-1335 2010);
FORCEPROP 2 LASTPIN (-1325 2100) $PN 193
J 2
(-1335 2110);
DISPLAY 0.617021 (-1335 2110);
PAINT ORANGE (-1335 2110);
FORCEPROP 2 LASTPIN (-1325 3400) $PN 141
J 2
(-1335 3410);
DISPLAY 0.617021 (-1335 3410);
PAINT ORANGE (-1335 3410);
FORCEPROP 2 LASTPIN (-1325 3450) $PN 139
J 2
(-1335 3460);
DISPLAY 0.617021 (-1335 3460);
PAINT ORANGE (-1335 3460);
FORCEPROP 2 LASTPIN (-1325 4150) $PN 111
J 2
(-1335 4160);
DISPLAY 0.617021 (-1335 4160);
PAINT ORANGE (-1335 4160);
FORCEPROP 2 LASTPIN (-1325 4250) $PN 107
J 2
(-1335 4260);
DISPLAY 0.617021 (-1335 4260);
PAINT ORANGE (-1335 4260);
FORCEPROP 1 LAST LOCATION J8G1
J 0
(-1300 4700);
DISPLAY 0.617021 (-1300 4700);
PAINT AQUA (-1300 4700);
FORCEPROP 2 LASTPIN (-625 4100) $PN 114
J 0
(-615 4110);
DISPLAY 0.617021 (-615 4110);
PAINT ORANGE (-615 4110);
FORCEPROP 2 LASTPIN (-625 4050) $PN 116
J 0
(-615 4060);
DISPLAY 0.617021 (-615 4060);
PAINT ORANGE (-615 4060);
FORCEPROP 2 LASTPIN (-625 4200) $PN 110
J 0
(-615 4210);
DISPLAY 0.617021 (-615 4210);
PAINT ORANGE (-615 4210);
FORCEPROP 2 LASTPIN (-625 3950) $PN 120
J 0
(-615 3960);
DISPLAY 0.617021 (-615 3960);
PAINT ORANGE (-615 3960);
FORCEPROP 2 LASTPIN (-625 4000) $PN 118
J 0
(-615 4010);
DISPLAY 0.617021 (-615 4010);
PAINT ORANGE (-615 4010);
FORCEPROP 2 LASTPIN (-1325 3250) $PN 147
J 2
(-1335 3260);
DISPLAY 0.617021 (-1335 3260);
PAINT ORANGE (-1335 3260);
FORCEPROP 2 LASTPIN (-1325 2200) $PN 189
J 2
(-1335 2210);
DISPLAY 0.617021 (-1335 2210);
PAINT ORANGE (-1335 2210);
FORCEPROP 2 LASTPIN (-1325 2150) $PN 191
J 2
(-1335 2160);
DISPLAY 0.617021 (-1335 2160);
PAINT ORANGE (-1335 2160);
FORCEPROP 2 LASTPIN (-1325 1950) $PN 199
J 2
(-1335 1960);
DISPLAY 0.617021 (-1335 1960);
PAINT ORANGE (-1335 1960);
FORCEPROP 2 LASTPIN (-1325 2650) $PN 171
J 2
(-1335 2660);
DISPLAY 0.617021 (-1335 2660);
PAINT ORANGE (-1335 2660);
FORCEPROP 2 LASTPIN (-625 3250) $PN 148
J 0
(-615 3260);
DISPLAY 0.617021 (-615 3260);
PAINT ORANGE (-615 3260);
FORCEPROP 1 LAST MATERIAL CONN
J 0
(-1275 4650);
DISPLAY 0.617021 (-1275 4650);
PAINT SKYBLUE (-1275 4650);
FORCEPROP 2 LASTPIN (-625 3600) $PN 134
J 0
(-615 3610);
DISPLAY 0.617021 (-615 3610);
PAINT ORANGE (-615 3610);
FORCEPROP 2 LASTPIN (-1325 4200) $PN 109
J 2
(-1335 4210);
DISPLAY 0.617021 (-1335 4210);
PAINT ORANGE (-1335 4210);
FORCEPROP 2 LASTPIN (-625 3800) $PN 126
J 0
(-615 3810);
DISPLAY 0.617021 (-615 3810);
PAINT ORANGE (-615 3810);
FORCEPROP 2 LASTPIN (-625 3700) $PN 130
J 0
(-615 3710);
DISPLAY 0.617021 (-615 3710);
PAINT ORANGE (-615 3710);
FORCEPROP 2 LASTPIN (-625 3650) $PN 132
J 0
(-615 3660);
DISPLAY 0.617021 (-615 3660);
PAINT ORANGE (-615 3660);
FORCEPROP 2 LASTPIN (-625 3550) $PN 136
J 0
(-615 3560);
DISPLAY 0.617021 (-615 3560);
PAINT ORANGE (-615 3560);
FORCEPROP 2 LASTPIN (-625 3500) $PN 138
J 0
(-615 3510);
DISPLAY 0.617021 (-615 3510);
PAINT ORANGE (-615 3510);
FORCEPROP 2 LASTPIN (-625 3300) $PN 146
J 0
(-615 3310);
DISPLAY 0.617021 (-615 3310);
PAINT ORANGE (-615 3310);
FORCEPROP 2 LASTPIN (-625 3400) $PN 142
J 0
(-615 3410);
DISPLAY 0.617021 (-615 3410);
PAINT ORANGE (-615 3410);
FORCEPROP 2 LASTPIN (-625 4350) $PN 104
J 0
(-615 4360);
DISPLAY 0.617021 (-615 4360);
PAINT ORANGE (-615 4360);
FORCEPROP 2 LASTPIN (-625 4400) $PN 102
J 0
(-615 4410);
DISPLAY 0.617021 (-615 4410);
PAINT ORANGE (-615 4410);
FORCEPROP 2 LASTPIN (-1325 4100) $PN 113
J 2
(-1335 4110);
DISPLAY 0.617021 (-1335 4110);
PAINT ORANGE (-1335 4110);
FORCEPROP 2 LASTPIN (-1325 4050) $PN 115
J 2
(-1335 4060);
DISPLAY 0.617021 (-1335 4060);
PAINT ORANGE (-1335 4060);
FORCEPROP 2 LASTPIN (-1325 4000) $PN 117
J 2
(-1335 4010);
DISPLAY 0.617021 (-1335 4010);
PAINT ORANGE (-1335 4010);
FORCEPROP 2 LASTPIN (-1325 3950) $PN 119
J 2
(-1335 3960);
DISPLAY 0.617021 (-1335 3960);
PAINT ORANGE (-1335 3960);
FORCEPROP 2 LASTPIN (-1325 3900) $PN 121
J 2
(-1335 3910);
DISPLAY 0.617021 (-1335 3910);
PAINT ORANGE (-1335 3910);
FORCEPROP 2 LASTPIN (-1325 3850) $PN 123
J 2
(-1335 3860);
DISPLAY 0.617021 (-1335 3860);
PAINT ORANGE (-1335 3860);
FORCEPROP 2 LASTPIN (-1325 3800) $PN 125
J 2
(-1335 3810);
DISPLAY 0.617021 (-1335 3810);
PAINT ORANGE (-1335 3810);
FORCEPROP 2 LASTPIN (-1325 3750) $PN 127
J 2
(-1335 3760);
DISPLAY 0.617021 (-1335 3760);
PAINT ORANGE (-1335 3760);
FORCEPROP 2 LASTPIN (-1325 3700) $PN 129
J 2
(-1335 3710);
DISPLAY 0.617021 (-1335 3710);
PAINT ORANGE (-1335 3710);
FORCEPROP 2 LASTPIN (-1325 3650) $PN 131
J 2
(-1335 3660);
DISPLAY 0.617021 (-1335 3660);
PAINT ORANGE (-1335 3660);
FORCEPROP 2 LASTPIN (-1325 3600) $PN 133
J 2
(-1335 3610);
DISPLAY 0.617021 (-1335 3610);
PAINT ORANGE (-1335 3610);
FORCEPROP 2 LASTPIN (-1325 3550) $PN 135
J 2
(-1335 3560);
DISPLAY 0.617021 (-1335 3560);
PAINT ORANGE (-1335 3560);
FORCEPROP 2 LASTPIN (-1325 3500) $PN 137
J 2
(-1335 3510);
DISPLAY 0.617021 (-1335 3510);
PAINT ORANGE (-1335 3510);
FORCEPROP 2 LASTPIN (-1325 3350) $PN 143
J 2
(-1335 3360);
DISPLAY 0.617021 (-1335 3360);
PAINT ORANGE (-1335 3360);
FORCEPROP 2 LASTPIN (-1325 3300) $PN 145
J 2
(-1335 3310);
DISPLAY 0.617021 (-1335 3310);
PAINT ORANGE (-1335 3310);
FORCEPROP 2 LASTPIN (-1325 2900) $PN 161
J 2
(-1335 2910);
DISPLAY 0.617021 (-1335 2910);
PAINT ORANGE (-1335 2910);
FORCEPROP 2 LASTPIN (-1325 2950) $PN 159
J 2
(-1335 2960);
DISPLAY 0.617021 (-1335 2960);
PAINT ORANGE (-1335 2960);
FORCEPROP 2 LASTPIN (-1325 3000) $PN 157
J 2
(-1335 3010);
DISPLAY 0.617021 (-1335 3010);
PAINT ORANGE (-1335 3010);
FORCEPROP 2 LASTPIN (-625 3200) $PN 150
J 0
(-615 3210);
DISPLAY 0.617021 (-615 3210);
PAINT ORANGE (-615 3210);
FORCEPROP 2 LASTPIN (-625 3150) $PN 152
J 0
(-615 3160);
DISPLAY 0.617021 (-615 3160);
PAINT ORANGE (-615 3160);
FORCEPROP 2 LASTPIN (-625 3100) $PN 154
J 0
(-615 3110);
DISPLAY 0.617021 (-615 3110);
PAINT ORANGE (-615 3110);
FORCEPROP 2 LASTPIN (-625 2900) $PN 162
J 0
(-615 2910);
DISPLAY 0.617021 (-615 2910);
PAINT ORANGE (-615 2910);
FORCEPROP 2 LASTPIN (-625 2750) $PN 168
J 0
(-615 2760);
DISPLAY 0.617021 (-615 2760);
PAINT ORANGE (-615 2760);
FORCEPROP 2 LASTPIN (-625 2650) $PN 172
J 0
(-615 2660);
DISPLAY 0.617021 (-615 2660);
PAINT ORANGE (-615 2660);
FORCEPROP 2 LASTPIN (-625 2850) $PN 164
J 0
(-615 2860);
DISPLAY 0.617021 (-615 2860);
PAINT ORANGE (-615 2860);
FORCEPROP 2 LASTPIN (-625 2600) $PN 174
J 0
(-615 2610);
DISPLAY 0.617021 (-615 2610);
PAINT ORANGE (-615 2610);
FORCEPROP 2 LASTPIN (-625 2700) $PN 170
J 0
(-615 2710);
DISPLAY 0.617021 (-615 2710);
PAINT ORANGE (-615 2710);
FORCEPROP 2 LASTPIN (-625 2550) $PN 176
J 0
(-615 2560);
DISPLAY 0.617021 (-615 2560);
PAINT ORANGE (-615 2560);
FORCEPROP 2 LASTPIN (-625 2500) $PN 178
J 0
(-615 2510);
DISPLAY 0.617021 (-615 2510);
PAINT ORANGE (-615 2510);
FORCEPROP 2 LASTPIN (-625 2450) $PN 180
J 0
(-615 2460);
DISPLAY 0.617021 (-615 2460);
PAINT ORANGE (-615 2460);
FORCEPROP 2 LASTPIN (-625 2400) $PN 182
J 0
(-615 2410);
DISPLAY 0.617021 (-615 2410);
PAINT ORANGE (-615 2410);
FORCEPROP 2 LASTPIN (-625 2800) $PN 166
J 0
(-615 2810);
DISPLAY 0.617021 (-615 2810);
PAINT ORANGE (-615 2810);
FORCEPROP 1 LAST PATH I78
J 0
(-875 4650);
PAINT GREEN (-875 4650);
DISPLAY INVISIBLE (-875 4650);
FORCEPROP 1 LAST PACK_TYPE SM
J 0
(-1275 4750);
PAINT SKYBLUE (-1275 4750);
DISPLAY INVISIBLE (-1275 4750);
FORCEPROP 0 LAST ROOM IO_SLOT
J 0
(-1275 4725);
DISPLAY 1.021277 (-1275 4725);
PAINT ORANGE (-1275 4725);
DISPLAY INVISIBLE (-1275 4725);
FORCEPROP 2 LAST SEC_TYPE SM
J 0
(-875 4700);
DISPLAY 1.021277 (-875 4700);
PAINT ORANGE (-875 4700);
DISPLAY INVISIBLE (-875 4700);
FORCEPROP 2 LAST CDS_LIB mstr_sconn
J 0
(-975 3200);
PAINT MONO (-975 3200);
DISPLAY INVISIBLE (-975 3200);
FORCEPROP 1 LAST CDS_LMAN_SYM_OUTLINE -300,1350,300,-1350
J 0
(-975 3200);
DISPLAY 0.468085 (-975 3200);
PAINT GREEN (-975 3200);
DISPLAY INVISIBLE (-975 3200);
FORCEPROP 2 LAST SEC 2
J 0
(-875 4700);
DISPLAY 0.680851 (-875 4700);
PAINT MONO (-875 4700);
DISPLAY INVISIBLE (-875 4700);
FORCEADD TAP..1
R 2
(-2025 2050);
FORCEPROP 3 LASTPIN (-1975 2050) SIG_NAME P3E_CPU0_PE2_SS_C_TXP<7>
J 0
(-1965 2060);
DISPLAY 0.659574 (-1965 2060);
PAINT MONO (-1965 2060);
DISPLAY INVISIBLE (-1965 2060);
FORCEPROP 1 LASTPIN (-1975 2050) BN 7
J 2
(-1963 2058);
DISPLAY 0.617021 (-1963 2058);
PAINT GREEN (-1963 2058);
FORCEPROP 1 LAST PATH I8
J 2
(-2023 2050);
DISPLAY 0.872340 (-2023 2050);
PAINT GREEN (-2023 2050);
DISPLAY INVISIBLE (-2023 2050);
FORCEPROP 1 LAST HDL_TAP TRUE
J 2
(-2350 1925);
DISPLAY 0.872340 (-2350 1925);
PAINT ORANGE (-2350 1925);
DISPLAY INVISIBLE (-2350 1925);
FORCEPROP 1 LAST BODY_TYPE PLUMBING
J 2
(-2025 2100);
DISPLAY 0.872340 (-2025 2100);
PAINT GREEN (-2025 2100);
DISPLAY INVISIBLE (-2025 2100);
FORCEPROP 2 LAST CDS_LIB mstr_standard
J 0
(-2025 2050);
PAINT MONO (-2025 2050);
DISPLAY INVISIBLE (-2025 2050);
FORCEADD TAP..1
R 2
(-2025 2200);
FORCEPROP 3 LASTPIN (-1975 2200) SIG_NAME P3E_CPU0_PE2_SS_C_TXP<6>
J 0
(-1965 2210);
DISPLAY 0.659574 (-1965 2210);
PAINT MONO (-1965 2210);
DISPLAY INVISIBLE (-1965 2210);
FORCEPROP 1 LASTPIN (-1975 2200) BN 6
J 2
(-1963 2208);
DISPLAY 0.617021 (-1963 2208);
PAINT GREEN (-1963 2208);
FORCEPROP 1 LAST PATH I9
J 2
(-2023 2200);
DISPLAY 0.872340 (-2023 2200);
PAINT GREEN (-2023 2200);
DISPLAY INVISIBLE (-2023 2200);
FORCEPROP 1 LAST HDL_TAP TRUE
J 2
(-2350 2075);
DISPLAY 0.872340 (-2350 2075);
PAINT ORANGE (-2350 2075);
DISPLAY INVISIBLE (-2350 2075);
FORCEPROP 1 LAST BODY_TYPE PLUMBING
J 2
(-2025 2250);
DISPLAY 0.872340 (-2025 2250);
PAINT GREEN (-2025 2250);
DISPLAY INVISIBLE (-2025 2250);
FORCEPROP 2 LAST CDS_LIB mstr_standard
J 0
(-2025 2200);
PAINT MONO (-2025 2200);
DISPLAY INVISIBLE (-2025 2200);
FORCEADD INTEL_CORP_BPAGE..1
(2650 500);
FORCEPROP 1 LAST CDS_CON_LAST_MODIFIED Tue Dec 01 11:51:54 2015
J 0
(1225 825);
PAINT ORANGE (1225 825);
DISPLAY INVISIBLE (1225 825);
FORCEPROP 1 LAST CUSTOM_TXT_CDS <CURRENT_DESIGN_SHEET> OF <TOTAL_DESIGN_SHEETS>
J 0
(2150 525);
PAINT GREEN (2150 525);
FORCEPROP 1 LAST CUSTOM_TXT_CDS <CON_LAST_MODIFIED>
J 0
(725 850);
PAINT GREEN (725 850);
FORCEPROP 2 LAST CUSTOM_TXT_CDS <XR_PAGE_TITLE>
J 0
(-5240 5750);
DISPLAY 0.638298 (-5240 5750);
PAINT PINK (-5240 5750);
DISPLAY INVISIBLE (-5240 5750);
FORCEPROP 1 LAST SCH_ADDRESS1 2200 Mission College Blvd.
J 0
(-1325 625);
DISPLAY 0.617021 (-1325 625);
PAINT GREEN (-1325 625);
FORCEPROP 1 LAST SCH_ADDRESS2 P.O. BOX 58119
J 0
(-1325 575);
DISPLAY 0.617021 (-1325 575);
PAINT GREEN (-1325 575);
FORCEPROP 1 LAST SCH_ADDRESS3 Santa Clara, CA 95052-8119
J 0
(-1325 525);
DISPLAY 0.617021 (-1325 525);
PAINT GREEN (-1325 525);
FORCEPROP 1 LAST SCH_DEPT BESD
J 1
(-1800 600);
DISPLAY 1.212766 (-1800 600);
PAINT YELLOW (-1800 600);
FORCEPROP 1 LAST SCH_REV 2.420
J 0
(2400 650);
DISPLAY 0.978723 (2400 650);
PAINT YELLOW (2400 650);
FORCEPROP 1 LAST SCH_NUMBER H4694802
J 0
(1350 650);
DISPLAY 1.212766 (1350 650);
PAINT YELLOW (1350 650);
FORCEPROP 1 LAST SCH_TITLE X24 SLOT (2 OF 2)
J 0
(-5300 550);
DISPLAY 1.212766 (-5300 550);
PAINT ORANGE (-5300 550);
FORCEPROP 1 LAST COMMENT_BODY TRUE
J 0
(2662 512);
DISPLAY 0.468085 (2662 512);
PAINT GREEN (2662 512);
DISPLAY INVISIBLE (2662 512);
FORCEPROP 2 LAST PAGE_BORDER TRUE
J 0
(-5240 5750);
DISPLAY 0.851064 (-5240 5750);
PAINT PINK (-5240 5750);
DISPLAY INVISIBLE (-5240 5750);
FORCEPROP 2 LAST CDS_LIB mstr_symbols
J 0
(2650 500);
PAINT MONO (2650 500);
DISPLAY INVISIBLE (2650 500);
FORCEPROP 2 LAST CDS_XR_PAGE_TITLE CR-109 : @BASEBOARD_FAB2_LIB.BASEBOARD_FAB2(SCH_1):PAGE109
J 0
(-5240 5750);
DISPLAY 0.638298 (-5240 5750);
PAINT PINK (-5240 5750);
DISPLAY INVISIBLE (-5240 5750);
WIRE 17 -1 (-2075 3625)(-2075 3425);
WIRE 17 -1 (-2075 3775)(-2075 3625);
WIRE 17 -1 (-2075 3425)(-2075 3325);
WIRE 17 -1 (-2075 3875)(-2075 3775);
WIRE 17 -1 (-2075 4075)(-2075 3875);
WIRE 17 -1 (-2075 4225)(-2075 4075);
WIRE 17 -1 (-2075 4375)(-2075 4225);
WIRE 17 -1 (-2075 4500)(-2075 4375);
WIRE 17 -1 (-3400 4500)(-2075 4500);
FORCEPROP 2 LAST SIG_NAME P3E_CPU0_PE1_SS_C_TXN<7:0>
J 0
(-3396 4520);
DISPLAY 0.680851 (-3396 4520);
PAINT ORANGE (-3396 4520);
WIRE 17 -1 (-2075 3100)(-2075 3125);
WIRE 17 -1 (-2075 3025)(-2075 3100);
WIRE 17 -1 (-2075 3100)(-3375 3100);
FORCEPROP 2 LAST SIG_NAME P3E_CPU0_PE2_SS_C_TXP<7:0>
J 0
(-3335 3110);
DISPLAY 0.680851 (-3335 3110);
PAINT ORANGE (-3335 3110);
WIRE 17 -1 (-2075 2825)(-2075 2675);
WIRE 17 -1 (-2075 3025)(-2075 2825);
WIRE 17 -1 (-2075 2675)(-2075 2525);
WIRE 17 -1 (-2075 2525)(-2075 2375);
WIRE 17 -1 (-2075 2375)(-2075 2225);
WIRE 17 -1 (-2075 2225)(-2075 2075);
WIRE 17 -1 (-2325 2975)(-2325 3175);
WIRE 17 -1 (-2325 2975)(-2325 2875);
WIRE 17 -1 (-3375 3175)(-2325 3175);
FORCEPROP 2 LAST SIG_NAME P3E_CPU0_PE2_SS_C_TXN<7:0>
J 0
(-3360 3185);
DISPLAY 0.680851 (-3360 3185);
PAINT ORANGE (-3360 3185);
WIRE 17 -1 (-2325 2275)(-2325 2125);
WIRE 17 -1 (-2325 2425)(-2325 2275);
WIRE 17 -1 (-2325 2575)(-2325 2425);
WIRE 17 -1 (-2325 2725)(-2325 2575);
WIRE 17 -1 (-2325 2875)(-2325 2725);
WIRE 17 -1 (-200 2775)(-200 2675);
WIRE 17 -1 (-200 2975)(-200 2775);
WIRE 17 -1 (-200 2675)(-200 2525);
WIRE 17 -1 (-200 2525)(-200 2375);
WIRE 17 -1 (-200 3125)(-200 2975);
WIRE 17 -1 (-200 3150)(-200 3125);
WIRE 17 -1 (-200 2375)(-200 2175);
WIRE 17 -1 (-200 2175)(-200 2075);
WIRE 17 -1 (-200 3150)(825 3150);
FORCEPROP 2 LAST SIG_NAME P3E_CPU0_PE2_SS_RXN<7:0>
J 0
(65 3160);
DISPLAY 0.617021 (65 3160);
PAINT ORANGE (65 3160);
WIRE 17 -1 (-200 3425)(-200 3275);
WIRE 17 -1 (-200 3525)(-200 3425);
WIRE 17 -1 (-200 3725)(-200 3525);
WIRE 17 -1 (-200 3875)(-200 3725);
WIRE 17 -1 (-200 4025)(-200 3875);
WIRE 17 -1 (-200 4175)(-200 4025);
WIRE 17 -1 (-200 4325)(-200 4175);
WIRE 17 -1 (-200 4375)(-200 4325);
WIRE 17 -1 (-200 4375)(825 4375);
FORCEPROP 2 LAST SIG_NAME P3E_CPU0_PE1_SS_R_RXN<7:0>
J 0
(-185 4385);
DISPLAY 0.680851 (-185 4385);
PAINT ORANGE (-185 4385);
WIRE 17 -1 (25 2625)(25 2475);
WIRE 17 -1 (25 2825)(25 2625);
WIRE 17 -1 (25 2475)(25 2325);
WIRE 17 -1 (25 2325)(25 2225);
WIRE 17 -1 (25 2925)(25 2825);
WIRE 17 -1 (25 3075)(25 2925);
WIRE 17 -1 (25 2225)(25 2025);
WIRE 17 -1 (825 3075)(25 3075);
FORCEPROP 2 LAST SIG_NAME P3E_CPU0_PE2_SS_RXP<7:0>
J 0
(65 3085);
DISPLAY 0.617021 (65 3085);
PAINT ORANGE (65 3085);
WIRE 17 -1 (25 3375)(25 3225);
WIRE 17 -1 (25 3575)(25 3375);
WIRE 17 -1 (25 3675)(25 3575);
WIRE 17 -1 (25 3825)(25 3675);
WIRE 17 -1 (25 3975)(25 3825);
WIRE 17 -1 (25 4125)(25 3975);
WIRE 17 -1 (25 4275)(25 4125);
WIRE 17 -1 (25 4300)(25 4275);
WIRE 17 -1 (25 4300)(825 4300);
FORCEPROP 2 LAST SIG_NAME P3E_CPU0_PE1_SS_R_RXP<7:0>
J 0
(65 4310);
DISPLAY 0.680851 (65 4310);
PAINT ORANGE (65 4310);
WIRE 17 -1 (-2325 4425)(-2325 4325);
WIRE 17 -1 (-3400 4425)(-2325 4425);
FORCEPROP 2 LAST SIG_NAME P3E_CPU0_PE1_SS_C_TXP<7:0>
J 0
(-3385 4435);
DISPLAY 0.680851 (-3385 4435);
PAINT ORANGE (-3385 4435);
WIRE 17 -1 (-2325 4325)(-2325 4175);
WIRE 17 -1 (-2325 4175)(-2325 4025);
WIRE 17 -1 (-2325 4025)(-2325 3925);
WIRE 17 -1 (-2325 3925)(-2325 3725);
WIRE 17 -1 (-2325 3725)(-2325 3575);
WIRE 17 -1 (-2325 3575)(-2325 3475);
WIRE 17 -1 (-2325 3475)(-2325 3275);
WIRE 17 -1 (-200 4475)(-200 4425);
WIRE 17 -1 (-200 4475)(825 4475);
FORCEPROP 2 LAST SIG_NAME P3E_CPU0_PE1_PCH_CON_RXP<15:8>
J 0
(-135 4485);
DISPLAY 0.680851 (-135 4485);
PAINT ORANGE (-135 4485);
WIRE 16 -1 (-1325 4400)(-1500 4400);
WIRE 16 -1 (-1500 4400)(-1500 4250);
WIRE 16 -1 (-1325 4250)(-1500 4250);
WIRE 16 -1 (-1500 4250)(-1500 4100);
WIRE 16 -1 (-1325 4100)(-1500 4100);
WIRE 16 -1 (-1500 4100)(-1500 3950);
WIRE 16 -1 (-1325 3950)(-1500 3950);
WIRE 16 -1 (-1500 3950)(-1500 3800);
WIRE 16 -1 (-1325 3800)(-1500 3800);
WIRE 16 -1 (-1500 3800)(-1500 3650);
WIRE 16 -1 (-1325 3650)(-1500 3650);
WIRE 16 -1 (-1500 3650)(-1500 3500);
WIRE 16 -1 (-1325 3500)(-1500 3500);
WIRE 16 -1 (-1500 3500)(-1500 3350);
WIRE 16 -1 (-1325 3350)(-1500 3350);
WIRE 16 -1 (-1500 3350)(-1500 3200);
WIRE 16 -1 (-1325 3200)(-1500 3200);
WIRE 16 -1 (-1500 3200)(-1500 3050);
WIRE 16 -1 (-1325 3050)(-1500 3050);
WIRE 16 -1 (-1500 3050)(-1500 2900);
WIRE 16 -1 (-1325 2900)(-1500 2900);
WIRE 16 -1 (-1500 2900)(-1500 2750);
WIRE 16 -1 (-1325 2750)(-1500 2750);
WIRE 16 -1 (-1500 2750)(-1500 2600);
WIRE 16 -1 (-1325 2600)(-1500 2600);
WIRE 16 -1 (-1500 2600)(-1500 2450);
WIRE 16 -1 (-1325 2450)(-1500 2450);
WIRE 16 -1 (-1500 2450)(-1500 2300);
WIRE 16 -1 (-1325 2300)(-1500 2300);
WIRE 16 -1 (-1500 2300)(-1500 2150);
WIRE 16 -1 (-1325 2150)(-1500 2150);
WIRE 16 -1 (-1500 2150)(-1500 2000);
WIRE 16 -1 (-1325 2000)(-1500 2000);
WIRE 16 -1 (-1500 2000)(-1500 1750);
WIRE 16 -1 (-625 4350)(-450 4350);
WIRE 16 -1 (-450 4350)(-450 4200);
WIRE 16 -1 (-450 4200)(-625 4200);
WIRE 16 -1 (-450 4200)(-450 4050);
WIRE 16 -1 (-450 4050)(-450 3900);
WIRE 16 -1 (-450 4050)(-625 4050);
WIRE 16 -1 (-450 3900)(-450 3750);
WIRE 16 -1 (-450 3900)(-625 3900);
WIRE 16 -1 (-450 3750)(-450 3600);
WIRE 16 -1 (-450 3750)(-625 3750);
WIRE 16 -1 (-450 3600)(-450 3450);
WIRE 16 -1 (-450 3600)(-625 3600);
WIRE 16 -1 (-450 3450)(-450 3300);
WIRE 16 -1 (-450 3450)(-625 3450);
WIRE 16 -1 (-450 3300)(-450 3150);
WIRE 16 -1 (-450 3300)(-625 3300);
WIRE 16 -1 (-450 3150)(-625 3150);
WIRE 16 -1 (-450 3150)(-450 3000);
WIRE 16 -1 (-450 3000)(-450 2850);
WIRE 16 -1 (-450 3000)(-625 3000);
WIRE 16 -1 (-450 2850)(-450 2700);
WIRE 16 -1 (-450 2850)(-625 2850);
WIRE 16 -1 (-450 2700)(-450 2550);
WIRE 16 -1 (-450 2700)(-625 2700);
WIRE 16 -1 (-450 2550)(-450 2400);
WIRE 16 -1 (-450 2550)(-625 2550);
WIRE 16 -1 (-450 2400)(-450 2250);
WIRE 16 -1 (-450 2400)(-625 2400);
WIRE 16 -1 (-450 2250)(-450 2100);
WIRE 16 -1 (-450 2250)(-625 2250);
WIRE 16 -1 (-450 2100)(-625 2100);
WIRE 16 -1 (-450 2100)(-450 1950);
WIRE 16 -1 (-450 1950)(-450 1750);
WIRE 16 -1 (-450 1950)(-625 1950);
WIRE 16 -1 (-1325 3300)(-1975 3300);
WIRE 16 -1 (-625 2900)(-75 2900);
WIRE 3 2175 (-4175 4875)(2025 4875);
WIRE 3 2175 (-4175 4875)(-4175 1150);
WIRE 3 2175 (2025 4875)(2025 1150);
WIRE 3 2175 (-4175 1150)(2025 1150);
WIRE 16 -1 (-625 3400)(-300 3400);
WIRE 16 -1 (-1975 2350)(-1325 2350);
WIRE 16 -1 (-2825 1950)(-1325 1950);
FORCEPROP 0 LAST SIG_NAME FM_PRSNT_2_6_N
J 0
(-2685 1960);
DISPLAY 0.617021 (-2685 1960);
PAINT ORANGE (-2685 1960);
WIRE 16 -1 (-1975 2050)(-1325 2050);
WIRE 16 -1 (-625 4250)(-75 4250);
WIRE 16 -1 (-1325 2200)(-1975 2200);
WIRE 16 -1 (-1325 2250)(-2225 2250);
WIRE 16 -1 (-2225 2400)(-1325 2400);
WIRE 16 -1 (-2225 2550)(-1325 2550);
WIRE 16 -1 (-1325 2700)(-2225 2700);
WIRE 16 -1 (-1975 2800)(-1325 2800);
WIRE 16 -1 (-2225 2850)(-1325 2850);
WIRE 16 -1 (-1975 3000)(-1325 3000);
WIRE 16 -1 (-2225 3150)(-1325 3150);
WIRE 16 -1 (-1325 3250)(-2225 3250);
WIRE 16 -1 (-1325 3450)(-2225 3450);
WIRE 16 -1 (-625 2350)(-300 2350);
WIRE 16 -1 (-625 2600)(-75 2600);
WIRE 16 -1 (-625 2800)(-75 2800);
WIRE 16 -1 (-625 2950)(-300 2950);
WIRE 16 -1 (-625 2050)(-300 2050);
WIRE 16 -1 (-625 2150)(-300 2150);
WIRE 16 -1 (-625 2200)(-75 2200);
WIRE 16 -1 (-625 2300)(-75 2300);
WIRE 16 -1 (-625 3550)(-75 3550);
WIRE 16 -1 (-625 3050)(-75 3050);
WIRE 16 -1 (-625 2500)(-300 2500);
WIRE 16 -1 (-75 2000)(-625 2000);
WIRE 16 -1 (-625 3100)(-300 3100);
WIRE 16 -1 (-625 3950)(-75 3950);
WIRE 16 -1 (-625 4100)(-75 4100);
WIRE 16 -1 (-625 3800)(-75 3800);
WIRE 16 -1 (-625 3650)(-75 3650);
WIRE 16 -1 (-625 4300)(-300 4300);
WIRE 16 -1 (-625 4400)(-300 4400);
WIRE 16 -1 (-625 4150)(-300 4150);
WIRE 16 -1 (-625 4000)(-300 4000);
WIRE 16 -1 (-625 3500)(-300 3500);
WIRE 16 -1 (-625 3850)(-300 3850);
WIRE 16 -1 (-625 3700)(-300 3700);
WIRE 16 -1 (-1325 3550)(-2225 3550);
WIRE 16 -1 (-1325 3700)(-2225 3700);
WIRE 16 -1 (-1325 3900)(-2225 3900);
WIRE 16 -1 (-1325 4000)(-2225 4000);
WIRE 16 -1 (-2225 4150)(-1325 4150);
WIRE 16 -1 (-1325 4300)(-2225 4300);
WIRE 16 -1 (-1325 3600)(-1975 3600);
WIRE 16 -1 (-1325 3750)(-1975 3750);
WIRE 16 -1 (-1325 3850)(-1975 3850);
WIRE 16 -1 (-1325 4050)(-1975 4050);
WIRE 16 -1 (-1975 4200)(-1325 4200);
WIRE 16 -1 (-1325 4350)(-1975 4350);
WIRE 16 -1 (-625 3350)(-75 3350);
WIRE 16 -1 (-625 3200)(-75 3200);
WIRE 16 -1 (-625 2450)(-75 2450);
WIRE 16 -1 (-625 3250)(-300 3250);
WIRE 16 -1 (-625 2750)(-300 2750);
WIRE 16 -1 (-625 2650)(-300 2650);
WIRE 16 -1 (-2225 2100)(-1325 2100);
WIRE 16 -1 (-2225 2950)(-1325 2950);
WIRE 16 -1 (-1975 2500)(-1325 2500);
WIRE 16 -1 (-1325 2650)(-1975 2650);
WIRE 16 -1 (-1975 3100)(-1325 3100);
WIRE 16 -1 (-1325 3400)(-1975 3400);
DOT 1 (-1500 2300);
DOT 1 (-2075 3100);
DOT 1 (-1500 2000);
DOT 1 (-1500 2150);
DOT 1 (-1500 2450);
DOT 1 (-1500 2600);
DOT 1 (-1500 2750);
DOT 1 (-1500 2900);
DOT 1 (-1500 3050);
DOT 1 (-1500 3200);
DOT 1 (-1500 3350);
DOT 1 (-450 2100);
DOT 1 (-450 1950);
DOT 1 (-450 2250);
DOT 1 (-450 2400);
DOT 1 (-450 2550);
DOT 1 (-450 2850);
DOT 1 (-450 2700);
DOT 1 (-450 3150);
DOT 1 (-450 3000);
DOT 1 (-450 3300);
DOT 1 (-1500 3650);
DOT 1 (-1500 3500);
DOT 1 (-1500 3800);
DOT 1 (-1500 3950);
DOT 1 (-1500 4100);
DOT 1 (-1500 4250);
DOT 1 (-450 3600);
DOT 1 (-450 3450);
DOT 1 (-450 3750);
DOT 1 (-450 3900);
DOT 1 (-450 4050);
DOT 1 (-450 4200);
FORCENOTE
TP FAB1 CHANGE PCIE TOPOLOGY 1116
(-1675 1475) 0;
DISPLAY LEFT (-1675 1475);
DISPLAY 1.702128 (-1675 1475);
PAINT RED (-1675 1475);
FORCENOTE
ROOM=IO_SLOT
(-5253 678) 0;
DISPLAY LEFT (-5253 678);
DISPLAY 2.510638 (-5253 678);
PAINT PURPLE (-5253 678);
QUIT
